FILE_TYPE = MACRO_DRAWING;
SET COLOR_WIRE YELLOW;
SET COLOR_PROP ORANGE;
SET COLOR_DOT WHITE;
SET COLOR_ARC YELLOW;
SET COLOR_BODY GREEN;
SET COLOR_NOTE PURPLE;
SET PROP_DISPLAY VALUE;
SET PAGE_NUMBER P211;
FORCEADD OFFPAGE..1
(-3325 4200);
FORCEPROP 2 LAST $XR1 219 
J 0
(-3727 4200);
DISPLAY 0.638298 (-3727 4200);
PAINT MONO (-3727 4200);
FORCEPROP 2 LAST $XR0 214 
J 0
(-3607 4200);
DISPLAY 0.638298 (-3607 4200);
PAINT MONO (-3607 4200);
FORCEPROP 2 LAST PATH I1
J 0
(-3600 4250);
DISPLAY 1.021277 (-3600 4250);
DISPLAY INVISIBLE (-3600 4250);
FORCEPROP 2 LAST CDS_LIB standard
J 0
(-3325 4200);
PAINT MONO (-3325 4200);
DISPLAY INVISIBLE (-3325 4200);
FORCEPROP 1 LAST OFFPAGE TRUE
J 0
(-3000 4075);
DISPLAY 0.872340 (-3000 4075);
PAINT GREEN (-3000 4075);
DISPLAY INVISIBLE (-3000 4075);
FORCEPROP 1 LAST COMMENT_BODY TRUE
J 0
(-3200 4100);
DISPLAY 0.872340 (-3200 4100);
PAINT GREEN (-3200 4100);
DISPLAY INVISIBLE (-3200 4100);
FORCEADD Q_RES..1
(-1625 3975);
FORCEPROP 1 LAST PART_NUMBER CS03322FB03
J 0
(-1750 4025);
DISPLAY 0.404255 (-1750 4025);
DISPLAY INVISIBLE (-1750 4025);
FORCEPROP 1 LAST TOLERANCE 1%
J 0
(-1450 3975);
DISPLAY 0.510638 (-1450 3975);
FORCEPROP 1 LAST VALUE 33.2
J 2
(-1475 3975);
DISPLAY 0.510638 (-1475 3975);
FORCEPROP 1 LAST PACK_TYPE 0402LF
J 0
(-1375 3975);
DISPLAY 0.510638 (-1375 3975);
FORCEPROP 1 LAST MATERIAL CHIP
J 0
(-1750 4050);
DISPLAY 0.404255 (-1750 4050);
FORCEPROP 1 LAST WATTAGE 1/16W
J 2
(-1525 4050);
DISPLAY 0.404255 (-1525 4050);
FORCEPROP 1 LAST $LOCATION R982
J 0
(-1850 3975);
DISPLAY 0.638298 (-1850 3975);
FORCEPROP 1 LASTPIN (-1725 3975) $PN 1
J 0
(-1713 3987);
DISPLAY 0.787234 (-1713 3987);
FORCEPROP 1 LASTPIN (-1525 3975) $PN 2
J 0
(-1563 3987);
DISPLAY 0.787234 (-1563 3987);
FORCEPROP 1 LAST PATH I10
J 0
(-1675 4125);
DISPLAY 0.978723 (-1675 4125);
PAINT WHITE (-1675 4125);
DISPLAY INVISIBLE (-1675 4125);
FORCEPROP 2 LAST CDS_LIB pure_quanta
J 0
(-1625 3975);
PAINT MONO (-1625 3975);
DISPLAY INVISIBLE (-1625 3975);
FORCEPROP 2 LAST CDS_LOCATION R982
J 0
(-1675 4175);
DISPLAY 1.021277 (-1675 4175);
DISPLAY INVISIBLE (-1675 4175);
FORCEPROP 2 LAST $SEC 1
J 0
(-1675 4175);
DISPLAY 0.680851 (-1675 4175);
PAINT MONO (-1675 4175);
DISPLAY INVISIBLE (-1675 4175);
FORCEPROP 2 LAST CDS_SEC 1
J 0
(-1675 4175);
DISPLAY 1.021277 (-1675 4175);
DISPLAY INVISIBLE (-1675 4175);
FORCEADD OFFPAGE..1
(1625 2850);
FORCEPROP 2 LAST $XR0 240 
J 0
(1343 2850);
DISPLAY 0.638298 (1343 2850);
PAINT MONO (1343 2850);
FORCEPROP 2 LAST PATH I100
J 0
(1375 2900);
DISPLAY 1.021277 (1375 2900);
DISPLAY INVISIBLE (1375 2900);
FORCEPROP 2 LAST CDS_LIB standard
J 0
(1625 2850);
PAINT MONO (1625 2850);
DISPLAY INVISIBLE (1625 2850);
FORCEPROP 1 LAST OFFPAGE TRUE
J 0
(1950 2725);
DISPLAY 0.872340 (1950 2725);
PAINT GREEN (1950 2725);
DISPLAY INVISIBLE (1950 2725);
FORCEPROP 1 LAST COMMENT_BODY TRUE
J 0
(1750 2750);
DISPLAY 0.872340 (1750 2750);
PAINT GREEN (1750 2750);
DISPLAY INVISIBLE (1750 2750);
FORCEADD OFFPAGE..1
(1625 2600);
FORCEPROP 2 LAST $XR0 240 
J 0
(1343 2600);
DISPLAY 0.638298 (1343 2600);
PAINT MONO (1343 2600);
FORCEPROP 2 LAST CDS_LIB standard
J 0
(1625 2600);
PAINT MONO (1625 2600);
DISPLAY INVISIBLE (1625 2600);
FORCEPROP 1 LAST OFFPAGE TRUE
J 0
(1950 2475);
DISPLAY 0.872340 (1950 2475);
PAINT GREEN (1950 2475);
DISPLAY INVISIBLE (1950 2475);
FORCEPROP 1 LAST COMMENT_BODY TRUE
J 0
(1750 2500);
DISPLAY 0.872340 (1750 2500);
PAINT GREEN (1750 2500);
DISPLAY INVISIBLE (1750 2500);
FORCEPROP 2 LAST PATH I101
J 0
(1375 2650);
DISPLAY 1.021277 (1375 2650);
DISPLAY INVISIBLE (1375 2650);
FORCEADD OFFPAGE..1
(1625 2375);
FORCEPROP 2 LAST $XR0 240 
J 0
(1343 2375);
DISPLAY 0.638298 (1343 2375);
PAINT MONO (1343 2375);
FORCEPROP 1 LAST COMMENT_BODY TRUE
J 0
(1750 2275);
DISPLAY 0.872340 (1750 2275);
PAINT GREEN (1750 2275);
DISPLAY INVISIBLE (1750 2275);
FORCEPROP 1 LAST OFFPAGE TRUE
J 0
(1950 2250);
DISPLAY 0.872340 (1950 2250);
PAINT GREEN (1950 2250);
DISPLAY INVISIBLE (1950 2250);
FORCEPROP 2 LAST CDS_LIB standard
J 0
(1625 2375);
PAINT MONO (1625 2375);
DISPLAY INVISIBLE (1625 2375);
FORCEPROP 2 LAST PATH I102
J 0
(1375 2425);
DISPLAY 1.021277 (1375 2425);
DISPLAY INVISIBLE (1375 2425);
FORCEADD OFFPAGE..1
(1625 2150);
FORCEPROP 2 LAST $XR0 240 
J 0
(1343 2150);
DISPLAY 0.638298 (1343 2150);
PAINT MONO (1343 2150);
FORCEPROP 1 LAST COMMENT_BODY TRUE
J 0
(1750 2050);
DISPLAY 0.872340 (1750 2050);
PAINT GREEN (1750 2050);
DISPLAY INVISIBLE (1750 2050);
FORCEPROP 1 LAST OFFPAGE TRUE
J 0
(1950 2025);
DISPLAY 0.872340 (1950 2025);
PAINT GREEN (1950 2025);
DISPLAY INVISIBLE (1950 2025);
FORCEPROP 2 LAST CDS_LIB standard
J 0
(1625 2150);
PAINT MONO (1625 2150);
DISPLAY INVISIBLE (1625 2150);
FORCEPROP 2 LAST PATH I104
J 0
(1325 2200);
DISPLAY 1.021277 (1325 2200);
DISPLAY INVISIBLE (1325 2200);
FORCEADD OFFPAGE..2
(4500 2150);
FORCEPROP 2 LAST $XR0 215 
J 0
(4689 2150);
DISPLAY 0.638298 (4689 2150);
PAINT MONO (4689 2150);
FORCEPROP 1 LAST COMMENT_BODY TRUE
J 0
(4455 2055);
DISPLAY 1.170213 (4455 2055);
PAINT GREEN (4455 2055);
DISPLAY INVISIBLE (4455 2055);
FORCEPROP 1 LAST OFFPAGE TRUE
J 0
(4825 2025);
DISPLAY 1.170213 (4825 2025);
PAINT GREEN (4825 2025);
DISPLAY INVISIBLE (4825 2025);
FORCEPROP 2 LAST CDS_LIB standard
J 0
(4500 2150);
PAINT MONO (4500 2150);
DISPLAY INVISIBLE (4500 2150);
FORCEPROP 2 LAST PATH I105
J 0
(4700 2200);
DISPLAY 1.021277 (4700 2200);
DISPLAY INVISIBLE (4700 2200);
FORCEADD OFFPAGE..4
(4500 1925);
FORCEPROP 2 LAST $XR0 215 
J 0
(4686 1925);
DISPLAY 0.638298 (4686 1925);
PAINT MONO (4686 1925);
FORCEPROP 2 LAST CDS_LIB standard
J 0
(4500 1925);
PAINT MONO (4500 1925);
DISPLAY INVISIBLE (4500 1925);
FORCEPROP 2 LAST PATH I108
J 0
(4700 1975);
DISPLAY 1.021277 (4700 1975);
DISPLAY INVISIBLE (4700 1975);
FORCEPROP 1 LAST OFFPAGE TRUE
J 0
(4825 1800);
DISPLAY 0.872340 (4825 1800);
PAINT GREEN (4825 1800);
DISPLAY INVISIBLE (4825 1800);
FORCEPROP 1 LAST COMMENT_BODY TRUE
J 0
(4475 1825);
DISPLAY 0.872340 (4475 1825);
PAINT PEACH (4475 1825);
DISPLAY INVISIBLE (4475 1825);
FORCEADD OFFPAGE..5
(1625 1925);
FORCEPROP 2 LAST $XR0 240 
J 0
(1370 1925);
DISPLAY 0.638298 (1370 1925);
PAINT MONO (1370 1925);
FORCEPROP 2 LAST CDS_LIB standard
J 0
(1625 1925);
PAINT MONO (1625 1925);
DISPLAY INVISIBLE (1625 1925);
FORCEPROP 2 LAST PATH I109
J 0
(1350 1975);
DISPLAY 1.021277 (1350 1975);
DISPLAY INVISIBLE (1350 1975);
FORCEPROP 1 LAST OFFPAGE TRUE
J 0
(1950 1800);
DISPLAY 0.872340 (1950 1800);
PAINT GREEN (1950 1800);
DISPLAY INVISIBLE (1950 1800);
FORCEPROP 1 LAST COMMENT_BODY TRUE
J 0
(1725 1850);
DISPLAY 0.872340 (1725 1850);
PAINT PEACH (1725 1850);
DISPLAY INVISIBLE (1725 1850);
FORCEADD OFFPAGE..2
(325 3500);
FORCEPROP 2 LAST $XR0 266 
J 0
(514 3500);
DISPLAY 0.638298 (514 3500);
PAINT MONO (514 3500);
FORCEPROP 2 LAST PATH I11
J 0
(500 3575);
DISPLAY 1.021277 (500 3575);
DISPLAY INVISIBLE (500 3575);
FORCEPROP 2 LAST CDS_LIB standard
J 0
(325 3500);
PAINT MONO (325 3500);
DISPLAY INVISIBLE (325 3500);
FORCEPROP 1 LAST OFFPAGE TRUE
J 0
(650 3375);
DISPLAY 1.170213 (650 3375);
PAINT GREEN (650 3375);
DISPLAY INVISIBLE (650 3375);
FORCEPROP 1 LAST COMMENT_BODY TRUE
J 0
(280 3405);
DISPLAY 1.170213 (280 3405);
PAINT GREEN (280 3405);
DISPLAY INVISIBLE (280 3405);
FORCEADD Q_RES..1
(3025 2150);
FORCEPROP 1 LAST PART_NUMBER CS03322FB03
J 0
(2925 2225);
DISPLAY 0.404255 (2925 2225);
DISPLAY INVISIBLE (2925 2225);
FORCEPROP 1 LAST TOLERANCE 1%
J 0
(3225 2150);
DISPLAY 0.404255 (3225 2150);
FORCEPROP 1 LAST PACK_TYPE 0402LF
J 0
(2925 2250);
DISPLAY 0.404255 (2925 2250);
FORCEPROP 1 LAST WATTAGE 1/16W
J 2
(3150 2250);
DISPLAY 0.404255 (3150 2250);
FORCEPROP 1 LAST VALUE 33.2
J 2
(3200 2150);
DISPLAY 0.404255 (3200 2150);
FORCEPROP 1 LAST MATERIAL CHIP
J 0
(3275 2150);
DISPLAY 0.404255 (3275 2150);
FORCEPROP 1 LAST $LOCATION R1811
J 0
(2775 2150);
DISPLAY 0.787234 (2775 2150);
FORCEPROP 1 LASTPIN (2925 2150) $PN 1
J 0
(2937 2162);
DISPLAY 0.787234 (2937 2162);
FORCEPROP 1 LASTPIN (3125 2150) $PN 2
J 0
(3087 2162);
DISPLAY 0.787234 (3087 2162);
FORCEPROP 2 LAST CDS_LIB pure_quanta
J 0
(3025 2150);
PAINT MONO (3025 2150);
DISPLAY INVISIBLE (3025 2150);
FORCEPROP 1 LAST PATH I110
J 0
(2975 2300);
DISPLAY 0.978723 (2975 2300);
PAINT WHITE (2975 2300);
DISPLAY INVISIBLE (2975 2300);
FORCEPROP 2 LAST CDS_LOCATION R1811
J 0
(2975 2350);
DISPLAY 1.021277 (2975 2350);
DISPLAY INVISIBLE (2975 2350);
FORCEPROP 2 LAST $SEC 1
J 0
(2975 2350);
DISPLAY 0.680851 (2975 2350);
PAINT MONO (2975 2350);
DISPLAY INVISIBLE (2975 2350);
FORCEPROP 2 LAST CDS_SEC 1
J 0
(2975 2350);
DISPLAY 1.021277 (2975 2350);
DISPLAY INVISIBLE (2975 2350);
FORCEADD Q_RES..1
(3025 1925);
FORCEPROP 1 LAST PART_NUMBER CS03322FB03
J 0
(2925 2000);
DISPLAY 0.404255 (2925 2000);
DISPLAY INVISIBLE (2925 2000);
FORCEPROP 1 LAST WATTAGE 1/16W
J 2
(3150 2025);
DISPLAY 0.404255 (3150 2025);
FORCEPROP 1 LAST PACK_TYPE 0402LF
J 0
(2925 2025);
DISPLAY 0.404255 (2925 2025);
FORCEPROP 1 LAST MATERIAL CHIP
J 0
(3275 1925);
DISPLAY 0.404255 (3275 1925);
FORCEPROP 1 LAST VALUE 33.2
J 2
(3200 1925);
DISPLAY 0.404255 (3200 1925);
FORCEPROP 1 LAST TOLERANCE 1%
J 0
(3225 1925);
DISPLAY 0.404255 (3225 1925);
FORCEPROP 1 LAST $LOCATION R1812
J 0
(2775 1925);
DISPLAY 0.787234 (2775 1925);
FORCEPROP 1 LASTPIN (2925 1925) $PN 1
J 0
(2937 1937);
DISPLAY 0.787234 (2937 1937);
FORCEPROP 1 LASTPIN (3125 1925) $PN 2
J 0
(3087 1937);
DISPLAY 0.787234 (3087 1937);
FORCEPROP 2 LAST CDS_LIB pure_quanta
J 0
(3025 1925);
PAINT MONO (3025 1925);
DISPLAY INVISIBLE (3025 1925);
FORCEPROP 1 LAST PATH I111
J 0
(2975 2075);
DISPLAY 0.978723 (2975 2075);
PAINT WHITE (2975 2075);
DISPLAY INVISIBLE (2975 2075);
FORCEPROP 2 LAST CDS_LOCATION R1812
J 0
(2975 2125);
DISPLAY 1.021277 (2975 2125);
DISPLAY INVISIBLE (2975 2125);
FORCEPROP 2 LAST $SEC 1
J 0
(2975 2125);
DISPLAY 0.680851 (2975 2125);
PAINT MONO (2975 2125);
DISPLAY INVISIBLE (2975 2125);
FORCEPROP 2 LAST CDS_SEC 1
J 0
(2975 2125);
DISPLAY 1.021277 (2975 2125);
DISPLAY INVISIBLE (2975 2125);
FORCEADD OFFPAGE..2
(4475 -600);
FORCEPROP 2 LAST $XR0 185 
J 0
(4664 -600);
DISPLAY 0.638298 (4664 -600);
PAINT MONO (4664 -600);
FORCEPROP 2 LAST CDS_LIB standard
J 0
(4475 -600);
PAINT MONO (4475 -600);
DISPLAY INVISIBLE (4475 -600);
FORCEPROP 1 LAST OFFPAGE TRUE
J 0
(4800 -725);
DISPLAY 1.170213 (4800 -725);
PAINT GREEN (4800 -725);
DISPLAY INVISIBLE (4800 -725);
FORCEPROP 1 LAST COMMENT_BODY TRUE
J 0
(4430 -695);
DISPLAY 1.170213 (4430 -695);
PAINT GREEN (4430 -695);
DISPLAY INVISIBLE (4430 -695);
FORCEPROP 2 LAST PATH I116
J 0
(4675 -550);
DISPLAY 1.021277 (4675 -550);
DISPLAY INVISIBLE (4675 -550);
FORCEADD OFFPAGE..2
(4475 -375);
FORCEPROP 2 LAST $XR0 185 
J 0
(4664 -375);
DISPLAY 0.638298 (4664 -375);
PAINT MONO (4664 -375);
FORCEPROP 1 LAST COMMENT_BODY TRUE
J 0
(4430 -470);
DISPLAY 1.170213 (4430 -470);
PAINT GREEN (4430 -470);
DISPLAY INVISIBLE (4430 -470);
FORCEPROP 1 LAST OFFPAGE TRUE
J 0
(4800 -500);
DISPLAY 1.170213 (4800 -500);
PAINT GREEN (4800 -500);
DISPLAY INVISIBLE (4800 -500);
FORCEPROP 2 LAST CDS_LIB standard
J 0
(4475 -375);
PAINT MONO (4475 -375);
DISPLAY INVISIBLE (4475 -375);
FORCEPROP 2 LAST PATH I117
J 0
(4675 -325);
DISPLAY 1.021277 (4675 -325);
DISPLAY INVISIBLE (4675 -325);
FORCEADD OFFPAGE..2
(325 3725);
FORCEPROP 2 LAST $XR0 274 
J 0
(514 3725);
DISPLAY 0.638298 (514 3725);
PAINT MONO (514 3725);
FORCEPROP 2 LAST PATH I12
J 0
(500 3800);
DISPLAY 1.021277 (500 3800);
DISPLAY INVISIBLE (500 3800);
FORCEPROP 2 LAST CDS_LIB standard
J 0
(325 3725);
PAINT MONO (325 3725);
DISPLAY INVISIBLE (325 3725);
FORCEPROP 1 LAST OFFPAGE TRUE
J 0
(650 3600);
DISPLAY 1.170213 (650 3600);
PAINT GREEN (650 3600);
DISPLAY INVISIBLE (650 3600);
FORCEPROP 1 LAST COMMENT_BODY TRUE
J 0
(280 3630);
DISPLAY 1.170213 (280 3630);
PAINT GREEN (280 3630);
DISPLAY INVISIBLE (280 3630);
FORCEADD OFFPAGE..1
(1600 -600);
FORCEPROP 2 LAST $XR0 215 
J 0
(1348 -600);
DISPLAY 0.638298 (1348 -600);
PAINT MONO (1348 -600);
FORCEPROP 2 LAST CDS_LIB standard
J 0
(1600 -600);
PAINT MONO (1600 -600);
DISPLAY INVISIBLE (1600 -600);
FORCEPROP 1 LAST OFFPAGE TRUE
J 0
(1925 -725);
DISPLAY 0.872340 (1925 -725);
PAINT GREEN (1925 -725);
DISPLAY INVISIBLE (1925 -725);
FORCEPROP 1 LAST COMMENT_BODY TRUE
J 0
(1725 -700);
DISPLAY 0.872340 (1725 -700);
PAINT GREEN (1725 -700);
DISPLAY INVISIBLE (1725 -700);
FORCEPROP 2 LAST PATH I120
J 0
(1300 -550);
DISPLAY 1.021277 (1300 -550);
DISPLAY INVISIBLE (1300 -550);
FORCEADD OFFPAGE..1
(1600 -375);
FORCEPROP 2 LAST $XR0 215 
J 0
(1348 -375);
DISPLAY 0.638298 (1348 -375);
PAINT MONO (1348 -375);
FORCEPROP 2 LAST CDS_LIB standard
J 0
(1600 -375);
PAINT MONO (1600 -375);
DISPLAY INVISIBLE (1600 -375);
FORCEPROP 1 LAST OFFPAGE TRUE
J 0
(1925 -500);
DISPLAY 0.872340 (1925 -500);
PAINT GREEN (1925 -500);
DISPLAY INVISIBLE (1925 -500);
FORCEPROP 1 LAST COMMENT_BODY TRUE
J 0
(1725 -475);
DISPLAY 0.872340 (1725 -475);
PAINT GREEN (1725 -475);
DISPLAY INVISIBLE (1725 -475);
FORCEPROP 2 LAST PATH I121
J 0
(1300 -325);
DISPLAY 1.021277 (1300 -325);
DISPLAY INVISIBLE (1300 -325);
FORCEADD Q_RES..1
(3000 -375);
FORCEPROP 1 LAST PART_NUMBER CS03322FB03
J 0
(2900 -300);
DISPLAY 0.404255 (2900 -300);
DISPLAY INVISIBLE (2900 -300);
FORCEPROP 1 LAST VALUE 33.2
J 2
(3175 -375);
DISPLAY 0.404255 (3175 -375);
FORCEPROP 1 LAST WATTAGE 1/16W
J 2
(3125 -275);
DISPLAY 0.404255 (3125 -275);
FORCEPROP 1 LAST PACK_TYPE 0402LF
J 0
(2900 -275);
DISPLAY 0.404255 (2900 -275);
FORCEPROP 1 LAST TOLERANCE 1%
J 0
(3200 -375);
DISPLAY 0.404255 (3200 -375);
FORCEPROP 1 LAST MATERIAL CHIP
J 0
(3250 -375);
DISPLAY 0.404255 (3250 -375);
FORCEPROP 1 LAST $LOCATION R1843
J 0
(2750 -375);
DISPLAY 0.638298 (2750 -375);
FORCEPROP 1 LASTPIN (2900 -375) $PN 1
J 0
(2912 -363);
DISPLAY 0.787234 (2912 -363);
FORCEPROP 1 LASTPIN (3100 -375) $PN 2
J 0
(3062 -363);
DISPLAY 0.787234 (3062 -363);
FORCEPROP 2 LAST CDS_LIB pure_quanta
J 0
(3000 -375);
PAINT MONO (3000 -375);
DISPLAY INVISIBLE (3000 -375);
FORCEPROP 1 LAST PATH I122
J 0
(2950 -225);
DISPLAY 0.978723 (2950 -225);
PAINT WHITE (2950 -225);
DISPLAY INVISIBLE (2950 -225);
FORCEPROP 2 LAST CDS_LOCATION R1843
J 0
(2950 -175);
DISPLAY 1.021277 (2950 -175);
DISPLAY INVISIBLE (2950 -175);
FORCEPROP 2 LAST $SEC 1
J 0
(2950 -175);
DISPLAY 0.680851 (2950 -175);
PAINT MONO (2950 -175);
DISPLAY INVISIBLE (2950 -175);
FORCEPROP 2 LAST CDS_SEC 1
J 0
(2950 -175);
DISPLAY 1.021277 (2950 -175);
DISPLAY INVISIBLE (2950 -175);
FORCEADD Q_RES..1
(3000 -600);
FORCEPROP 1 LAST PART_NUMBER CS03322FB03
J 0
(2900 -525);
DISPLAY 0.404255 (2900 -525);
DISPLAY INVISIBLE (2900 -525);
FORCEPROP 1 LAST WATTAGE 1/16W
J 2
(3125 -500);
DISPLAY 0.404255 (3125 -500);
FORCEPROP 1 LAST PACK_TYPE 0402LF
J 0
(2900 -500);
DISPLAY 0.404255 (2900 -500);
FORCEPROP 1 LAST TOLERANCE 1%
J 0
(3200 -600);
DISPLAY 0.404255 (3200 -600);
FORCEPROP 1 LAST VALUE 33.2
J 2
(3175 -600);
DISPLAY 0.404255 (3175 -600);
FORCEPROP 1 LAST MATERIAL CHIP
J 0
(3250 -600);
DISPLAY 0.404255 (3250 -600);
FORCEPROP 1 LAST $LOCATION R1844
J 0
(2750 -600);
DISPLAY 0.638298 (2750 -600);
FORCEPROP 1 LASTPIN (2900 -600) $PN 1
J 0
(2912 -588);
DISPLAY 0.787234 (2912 -588);
FORCEPROP 1 LASTPIN (3100 -600) $PN 2
J 0
(3062 -588);
DISPLAY 0.787234 (3062 -588);
FORCEPROP 2 LAST CDS_LIB pure_quanta
J 0
(3000 -600);
PAINT MONO (3000 -600);
DISPLAY INVISIBLE (3000 -600);
FORCEPROP 1 LAST PATH I123
J 0
(2950 -450);
DISPLAY 0.978723 (2950 -450);
PAINT WHITE (2950 -450);
DISPLAY INVISIBLE (2950 -450);
FORCEPROP 2 LAST CDS_LOCATION R1844
J 0
(2950 -400);
DISPLAY 1.021277 (2950 -400);
DISPLAY INVISIBLE (2950 -400);
FORCEPROP 2 LAST $SEC 1
J 0
(2950 -400);
DISPLAY 0.680851 (2950 -400);
PAINT MONO (2950 -400);
DISPLAY INVISIBLE (2950 -400);
FORCEPROP 2 LAST CDS_SEC 1
J 0
(2950 -400);
DISPLAY 1.021277 (2950 -400);
DISPLAY INVISIBLE (2950 -400);
FORCEADD OFFPAGE..2
(325 350);
FORCEPROP 2 LAST $XR0 213 
J 0
(514 350);
DISPLAY 0.638298 (514 350);
PAINT MONO (514 350);
FORCEPROP 2 LAST CDS_LIB standard
J 0
(325 350);
PAINT MONO (325 350);
DISPLAY INVISIBLE (325 350);
FORCEPROP 1 LAST OFFPAGE TRUE
J 0
(650 225);
DISPLAY 1.170213 (650 225);
PAINT GREEN (650 225);
DISPLAY INVISIBLE (650 225);
FORCEPROP 1 LAST COMMENT_BODY TRUE
J 0
(280 255);
DISPLAY 1.170213 (280 255);
PAINT GREEN (280 255);
DISPLAY INVISIBLE (280 255);
FORCEPROP 2 LAST PATH I125
J 0
(525 400);
DISPLAY 1.021277 (525 400);
DISPLAY INVISIBLE (525 400);
FORCEADD OFFPAGE..1
(-3325 350);
FORCEPROP 2 LAST $XR2 258 
J 0
(-3847 350);
DISPLAY 0.638298 (-3847 350);
PAINT MONO (-3847 350);
FORCEPROP 2 LAST $XR1 244 
J 0
(-3727 350);
DISPLAY 0.638298 (-3727 350);
PAINT MONO (-3727 350);
FORCEPROP 2 LAST $XR0 259 
J 0
(-3607 350);
DISPLAY 0.638298 (-3607 350);
PAINT MONO (-3607 350);
FORCEPROP 1 LAST COMMENT_BODY TRUE
J 0
(-3200 250);
DISPLAY 0.872340 (-3200 250);
PAINT GREEN (-3200 250);
DISPLAY INVISIBLE (-3200 250);
FORCEPROP 1 LAST OFFPAGE TRUE
J 0
(-3000 225);
DISPLAY 0.872340 (-3000 225);
PAINT GREEN (-3000 225);
DISPLAY INVISIBLE (-3000 225);
FORCEPROP 2 LAST CDS_LIB standard
J 0
(-3325 350);
PAINT MONO (-3325 350);
DISPLAY INVISIBLE (-3325 350);
FORCEPROP 2 LAST PATH I126
J 0
(-3625 400);
DISPLAY 1.021277 (-3625 400);
DISPLAY INVISIBLE (-3625 400);
FORCEADD Q_RES..1
(-1625 350);
FORCEPROP 1 LAST PART_NUMBER CS03322FB03
J 0
(-1725 425);
DISPLAY 0.510638 (-1725 425);
DISPLAY INVISIBLE (-1725 425);
FORCEPROP 1 LAST VALUE 33.2
J 2
(-1425 350);
DISPLAY 0.510638 (-1425 350);
FORCEPROP 1 LAST WATTAGE 1/16W
J 2
(-1450 475);
DISPLAY 0.510638 (-1450 475);
FORCEPROP 1 LAST PACK_TYPE 0402LF
J 0
(-1325 350);
DISPLAY 0.510638 (-1325 350);
FORCEPROP 1 LAST TOLERANCE 1%
J 0
(-1400 350);
DISPLAY 0.510638 (-1400 350);
FORCEPROP 1 LAST MATERIAL CHIP
J 0
(-1725 475);
DISPLAY 0.510638 (-1725 475);
FORCEPROP 1 LAST $LOCATION R1919
J 0
(-1875 350);
DISPLAY 0.808511 (-1875 350);
FORCEPROP 1 LASTPIN (-1725 350) $PN 1
J 0
(-1713 362);
DISPLAY 0.787234 (-1713 362);
PAINT MONO (-1713 362);
FORCEPROP 1 LASTPIN (-1525 350) $PN 2
J 0
(-1563 362);
DISPLAY 0.787234 (-1563 362);
PAINT MONO (-1563 362);
FORCEPROP 1 LAST PATH I127
J 0
(-1675 500);
DISPLAY 0.978723 (-1675 500);
PAINT WHITE (-1675 500);
DISPLAY INVISIBLE (-1675 500);
FORCEPROP 2 LAST CDS_LIB pure_quanta
J 0
(-1625 350);
DISPLAY INVISIBLE (-1625 350);
FORCEPROP 0 LAST CDS_LOCATION R1919
J 0
(-1450 500);
DISPLAY 1.021277 (-1450 500);
DISPLAY INVISIBLE (-1450 500);
FORCEPROP 0 LAST $SEC 1
J 0
(-1450 500);
DISPLAY 0.680851 (-1450 500);
PAINT MONO (-1450 500);
DISPLAY INVISIBLE (-1450 500);
FORCEPROP 0 LAST CDS_SEC 1
J 0
(-1450 500);
DISPLAY 1.021277 (-1450 500);
DISPLAY INVISIBLE (-1450 500);
FORCEADD OFFPAGE..2
(300 150);
FORCEPROP 2 LAST $XR0 246 
J 0
(489 150);
DISPLAY 0.638298 (489 150);
PAINT MONO (489 150);
FORCEPROP 2 LAST PATH I128
J 0
(500 200);
DISPLAY 1.021277 (500 200);
DISPLAY INVISIBLE (500 200);
FORCEPROP 1 LAST COMMENT_BODY TRUE
J 0
(255 55);
DISPLAY 1.170213 (255 55);
PAINT GREEN (255 55);
DISPLAY INVISIBLE (255 55);
FORCEPROP 1 LAST OFFPAGE TRUE
J 0
(625 25);
DISPLAY 1.170213 (625 25);
PAINT GREEN (625 25);
DISPLAY INVISIBLE (625 25);
FORCEPROP 2 LAST CDS_LIB standard
J 0
(300 150);
PAINT MONO (300 150);
DISPLAY INVISIBLE (300 150);
FORCEADD Q_RES..1
(-1650 150);
FORCEPROP 1 LAST PART_NUMBER CS03322FB03
J 0
(-1750 225);
DISPLAY 0.510638 (-1750 225);
DISPLAY INVISIBLE (-1750 225);
FORCEPROP 1 LAST MATERIAL CHIP
J 0
(-1750 275);
DISPLAY 0.510638 (-1750 275);
FORCEPROP 1 LAST VALUE 33.2
J 2
(-1450 150);
DISPLAY 0.510638 (-1450 150);
FORCEPROP 1 LAST TOLERANCE 1%
J 0
(-1425 150);
DISPLAY 0.510638 (-1425 150);
FORCEPROP 1 LAST PACK_TYPE 0402LF
J 0
(-1350 150);
DISPLAY 0.510638 (-1350 150);
FORCEPROP 1 LAST WATTAGE 1/16W
J 2
(-1475 275);
DISPLAY 0.510638 (-1475 275);
FORCEPROP 1 LAST $LOCATION R4267
J 0
(-1875 150);
DISPLAY 0.787234 (-1875 150);
FORCEPROP 1 LASTPIN (-1750 150) $PN 1
J 0
(-1738 162);
DISPLAY 0.787234 (-1738 162);
PAINT MONO (-1738 162);
FORCEPROP 1 LASTPIN (-1550 150) $PN 2
J 0
(-1588 162);
DISPLAY 0.787234 (-1588 162);
PAINT MONO (-1588 162);
FORCEPROP 2 LAST CDS_LIB pure_quanta
J 0
(-1650 150);
DISPLAY INVISIBLE (-1650 150);
FORCEPROP 1 LAST PATH I129
J 0
(-1700 300);
DISPLAY 0.978723 (-1700 300);
PAINT WHITE (-1700 300);
DISPLAY INVISIBLE (-1700 300);
FORCEPROP 0 LAST CDS_LOCATION R4267
J 0
(-1475 300);
DISPLAY 1.021277 (-1475 300);
DISPLAY INVISIBLE (-1475 300);
FORCEPROP 0 LAST $SEC 1
J 0
(-1475 300);
DISPLAY 0.680851 (-1475 300);
PAINT MONO (-1475 300);
DISPLAY INVISIBLE (-1475 300);
FORCEPROP 0 LAST CDS_SEC 1
J 0
(-1475 300);
DISPLAY 1.021277 (-1475 300);
DISPLAY INVISIBLE (-1475 300);
FORCEADD Q_RES..1
(-1625 3725);
FORCEPROP 1 LAST PART_NUMBER CS03322FB03
J 0
(-1750 3775);
DISPLAY 0.404255 (-1750 3775);
DISPLAY INVISIBLE (-1750 3775);
FORCEPROP 1 LAST TOLERANCE 1%
J 0
(-1450 3725);
DISPLAY 0.510638 (-1450 3725);
FORCEPROP 1 LAST VALUE 33.2
J 2
(-1475 3725);
DISPLAY 0.510638 (-1475 3725);
FORCEPROP 1 LAST WATTAGE 1/16W
J 2
(-1525 3800);
DISPLAY 0.404255 (-1525 3800);
FORCEPROP 1 LAST MATERIAL CHIP
J 0
(-1750 3800);
DISPLAY 0.404255 (-1750 3800);
FORCEPROP 1 LAST PACK_TYPE 0402LF
J 0
(-1375 3725);
DISPLAY 0.510638 (-1375 3725);
FORCEPROP 1 LAST $LOCATION R983
J 0
(-1850 3725);
DISPLAY 0.638298 (-1850 3725);
FORCEPROP 1 LASTPIN (-1725 3725) $PN 1
J 0
(-1713 3737);
DISPLAY 0.787234 (-1713 3737);
FORCEPROP 1 LASTPIN (-1525 3725) $PN 2
J 0
(-1563 3737);
DISPLAY 0.787234 (-1563 3737);
FORCEPROP 1 LAST PATH I13
J 0
(-1675 3875);
DISPLAY 0.978723 (-1675 3875);
PAINT WHITE (-1675 3875);
DISPLAY INVISIBLE (-1675 3875);
FORCEPROP 2 LAST CDS_LIB pure_quanta
J 0
(-1625 3725);
PAINT MONO (-1625 3725);
DISPLAY INVISIBLE (-1625 3725);
FORCEPROP 2 LAST CDS_LOCATION R983
J 0
(-1675 3925);
DISPLAY 1.021277 (-1675 3925);
DISPLAY INVISIBLE (-1675 3925);
FORCEPROP 2 LAST $SEC 1
J 0
(-1675 3925);
DISPLAY 0.680851 (-1675 3925);
PAINT MONO (-1675 3925);
DISPLAY INVISIBLE (-1675 3925);
FORCEPROP 2 LAST CDS_SEC 1
J 0
(-1675 3925);
DISPLAY 1.021277 (-1675 3925);
DISPLAY INVISIBLE (-1675 3925);
FORCEADD OFFPAGE..1
(-3325 3725);
FORCEPROP 2 LAST $XR1 219 
J 0
(-3727 3725);
DISPLAY 0.638298 (-3727 3725);
PAINT MONO (-3727 3725);
FORCEPROP 2 LAST $XR0 214 
J 0
(-3607 3725);
DISPLAY 0.638298 (-3607 3725);
PAINT MONO (-3607 3725);
FORCEPROP 2 LAST PATH I14
J 0
(-3600 3775);
DISPLAY 1.021277 (-3600 3775);
DISPLAY INVISIBLE (-3600 3775);
FORCEPROP 2 LAST CDS_LIB standard
J 0
(-3325 3725);
PAINT MONO (-3325 3725);
DISPLAY INVISIBLE (-3325 3725);
FORCEPROP 1 LAST OFFPAGE TRUE
J 0
(-3000 3600);
DISPLAY 0.872340 (-3000 3600);
PAINT GREEN (-3000 3600);
DISPLAY INVISIBLE (-3000 3600);
FORCEPROP 1 LAST COMMENT_BODY TRUE
J 0
(-3200 3625);
DISPLAY 0.872340 (-3200 3625);
PAINT GREEN (-3200 3625);
DISPLAY INVISIBLE (-3200 3625);
FORCEADD Q_RES..1
(-1625 3500);
FORCEPROP 1 LAST PART_NUMBER CS03322FB03
J 0
(-1750 3550);
DISPLAY 0.404255 (-1750 3550);
DISPLAY INVISIBLE (-1750 3550);
FORCEPROP 1 LAST TOLERANCE 1%
J 0
(-1450 3500);
DISPLAY 0.510638 (-1450 3500);
FORCEPROP 1 LAST VALUE 33.2
J 2
(-1475 3500);
DISPLAY 0.510638 (-1475 3500);
FORCEPROP 1 LAST WATTAGE 1/16W
J 2
(-1525 3575);
DISPLAY 0.404255 (-1525 3575);
FORCEPROP 1 LAST PACK_TYPE 0402LF
J 0
(-1375 3500);
DISPLAY 0.510638 (-1375 3500);
FORCEPROP 1 LAST MATERIAL CHIP
J 0
(-1750 3575);
DISPLAY 0.404255 (-1750 3575);
FORCEPROP 1 LAST $LOCATION R984
J 0
(-1850 3500);
DISPLAY 0.638298 (-1850 3500);
FORCEPROP 1 LASTPIN (-1725 3500) $PN 1
J 0
(-1713 3512);
DISPLAY 0.787234 (-1713 3512);
FORCEPROP 1 LASTPIN (-1525 3500) $PN 2
J 0
(-1563 3512);
DISPLAY 0.787234 (-1563 3512);
FORCEPROP 1 LAST PATH I15
J 0
(-1675 3650);
DISPLAY 0.978723 (-1675 3650);
PAINT WHITE (-1675 3650);
DISPLAY INVISIBLE (-1675 3650);
FORCEPROP 2 LAST CDS_LIB pure_quanta
J 0
(-1625 3500);
PAINT MONO (-1625 3500);
DISPLAY INVISIBLE (-1625 3500);
FORCEPROP 2 LAST CDS_LOCATION R984
J 0
(-1675 3700);
DISPLAY 1.021277 (-1675 3700);
DISPLAY INVISIBLE (-1675 3700);
FORCEPROP 2 LAST $SEC 1
J 0
(-1675 3700);
DISPLAY 0.680851 (-1675 3700);
PAINT MONO (-1675 3700);
DISPLAY INVISIBLE (-1675 3700);
FORCEPROP 2 LAST CDS_SEC 1
J 0
(-1675 3700);
DISPLAY 1.021277 (-1675 3700);
DISPLAY INVISIBLE (-1675 3700);
FORCEADD OFFPAGE..1
(-3325 3500);
FORCEPROP 2 LAST $XR1 219 
J 0
(-3727 3500);
DISPLAY 0.638298 (-3727 3500);
PAINT MONO (-3727 3500);
FORCEPROP 2 LAST $XR0 214 
J 0
(-3607 3500);
DISPLAY 0.638298 (-3607 3500);
PAINT MONO (-3607 3500);
FORCEPROP 2 LAST PATH I16
J 0
(-3600 3550);
DISPLAY 1.021277 (-3600 3550);
DISPLAY INVISIBLE (-3600 3550);
FORCEPROP 2 LAST CDS_LIB standard
J 0
(-3325 3500);
PAINT MONO (-3325 3500);
DISPLAY INVISIBLE (-3325 3500);
FORCEPROP 1 LAST OFFPAGE TRUE
J 0
(-3000 3375);
DISPLAY 0.872340 (-3000 3375);
PAINT GREEN (-3000 3375);
DISPLAY INVISIBLE (-3000 3375);
FORCEPROP 1 LAST COMMENT_BODY TRUE
J 0
(-3200 3400);
DISPLAY 0.872340 (-3200 3400);
PAINT GREEN (-3200 3400);
DISPLAY INVISIBLE (-3200 3400);
FORCEADD OFFPAGE..2
(325 2375);
FORCEPROP 2 LAST $XR0 284 
J 0
(514 2375);
DISPLAY 0.638298 (514 2375);
PAINT MONO (514 2375);
FORCEPROP 2 LAST PATH I17
J 0
(500 2450);
DISPLAY 1.021277 (500 2450);
DISPLAY INVISIBLE (500 2450);
FORCEPROP 2 LAST CDS_LIB standard
J 0
(325 2375);
PAINT MONO (325 2375);
DISPLAY INVISIBLE (325 2375);
FORCEPROP 1 LAST OFFPAGE TRUE
J 0
(650 2250);
DISPLAY 1.170213 (650 2250);
PAINT GREEN (650 2250);
DISPLAY INVISIBLE (650 2250);
FORCEPROP 1 LAST COMMENT_BODY TRUE
J 0
(280 2280);
DISPLAY 1.170213 (280 2280);
PAINT GREEN (280 2280);
DISPLAY INVISIBLE (280 2280);
FORCEADD OFFPAGE..2
(325 3075);
FORCEPROP 2 LAST $XR0 284 
J 0
(514 3075);
DISPLAY 0.638298 (514 3075);
PAINT MONO (514 3075);
FORCEPROP 2 LAST PATH I18
J 0
(500 3150);
DISPLAY 1.021277 (500 3150);
DISPLAY INVISIBLE (500 3150);
FORCEPROP 2 LAST CDS_LIB standard
J 0
(325 3075);
PAINT MONO (325 3075);
DISPLAY INVISIBLE (325 3075);
FORCEPROP 1 LAST OFFPAGE TRUE
J 0
(650 2950);
DISPLAY 1.170213 (650 2950);
PAINT GREEN (650 2950);
DISPLAY INVISIBLE (650 2950);
FORCEPROP 1 LAST COMMENT_BODY TRUE
J 0
(280 2980);
DISPLAY 1.170213 (280 2980);
PAINT GREEN (280 2980);
DISPLAY INVISIBLE (280 2980);
FORCEADD OFFPAGE..2
(325 2600);
FORCEPROP 2 LAST $XR0 292 
J 0
(514 2600);
DISPLAY 0.638298 (514 2600);
PAINT MONO (514 2600);
FORCEPROP 2 LAST PATH I19
J 0
(500 2675);
DISPLAY 1.021277 (500 2675);
DISPLAY INVISIBLE (500 2675);
FORCEPROP 2 LAST CDS_LIB standard
J 0
(325 2600);
PAINT MONO (325 2600);
DISPLAY INVISIBLE (325 2600);
FORCEPROP 1 LAST OFFPAGE TRUE
J 0
(650 2475);
DISPLAY 1.170213 (650 2475);
PAINT GREEN (650 2475);
DISPLAY INVISIBLE (650 2475);
FORCEPROP 1 LAST COMMENT_BODY TRUE
J 0
(280 2505);
DISPLAY 1.170213 (280 2505);
PAINT GREEN (280 2505);
DISPLAY INVISIBLE (280 2505);
FORCEADD OFFPAGE..2
(325 2850);
FORCEPROP 2 LAST $XR0 292 
J 0
(514 2850);
DISPLAY 0.638298 (514 2850);
PAINT MONO (514 2850);
FORCEPROP 2 LAST PATH I20
J 0
(500 2925);
DISPLAY 1.021277 (500 2925);
DISPLAY INVISIBLE (500 2925);
FORCEPROP 2 LAST CDS_LIB standard
J 0
(325 2850);
PAINT MONO (325 2850);
DISPLAY INVISIBLE (325 2850);
FORCEPROP 1 LAST OFFPAGE TRUE
J 0
(650 2725);
DISPLAY 1.170213 (650 2725);
PAINT GREEN (650 2725);
DISPLAY INVISIBLE (650 2725);
FORCEPROP 1 LAST COMMENT_BODY TRUE
J 0
(280 2755);
DISPLAY 1.170213 (280 2755);
PAINT GREEN (280 2755);
DISPLAY INVISIBLE (280 2755);
FORCEADD Q_RES..1
(-1625 3075);
FORCEPROP 1 LAST PART_NUMBER CS03322FB03
J 0
(-1750 3125);
DISPLAY 0.404255 (-1750 3125);
DISPLAY INVISIBLE (-1750 3125);
FORCEPROP 1 LAST TOLERANCE 1%
J 0
(-1450 3075);
DISPLAY 0.510638 (-1450 3075);
FORCEPROP 1 LAST VALUE 33.2
J 2
(-1475 3075);
DISPLAY 0.510638 (-1475 3075);
FORCEPROP 1 LAST PACK_TYPE 0402LF
J 0
(-1375 3075);
DISPLAY 0.510638 (-1375 3075);
FORCEPROP 1 LAST MATERIAL CHIP
J 0
(-1750 3150);
DISPLAY 0.404255 (-1750 3150);
FORCEPROP 1 LAST WATTAGE 1/16W
J 2
(-1525 3150);
DISPLAY 0.404255 (-1525 3150);
FORCEPROP 1 LAST $LOCATION R985
J 0
(-1850 3075);
DISPLAY 0.638298 (-1850 3075);
FORCEPROP 1 LASTPIN (-1725 3075) $PN 1
J 0
(-1713 3087);
DISPLAY 0.787234 (-1713 3087);
FORCEPROP 1 LASTPIN (-1525 3075) $PN 2
J 0
(-1563 3087);
DISPLAY 0.787234 (-1563 3087);
FORCEPROP 1 LAST PATH I21
J 0
(-1675 3225);
DISPLAY 0.978723 (-1675 3225);
PAINT WHITE (-1675 3225);
DISPLAY INVISIBLE (-1675 3225);
FORCEPROP 2 LAST CDS_LIB pure_quanta
J 0
(-1625 3075);
PAINT MONO (-1625 3075);
DISPLAY INVISIBLE (-1625 3075);
FORCEPROP 2 LAST CDS_LOCATION R985
J 0
(-1675 3275);
DISPLAY 1.021277 (-1675 3275);
DISPLAY INVISIBLE (-1675 3275);
FORCEPROP 2 LAST $SEC 1
J 0
(-1675 3275);
DISPLAY 0.680851 (-1675 3275);
PAINT MONO (-1675 3275);
DISPLAY INVISIBLE (-1675 3275);
FORCEPROP 2 LAST CDS_SEC 1
J 0
(-1675 3275);
DISPLAY 1.021277 (-1675 3275);
DISPLAY INVISIBLE (-1675 3275);
FORCEADD OFFPAGE..1
(-3325 3075);
FORCEPROP 2 LAST $XR1 219 
J 0
(-3727 3075);
DISPLAY 0.638298 (-3727 3075);
PAINT MONO (-3727 3075);
FORCEPROP 2 LAST $XR0 214 
J 0
(-3607 3075);
DISPLAY 0.638298 (-3607 3075);
PAINT MONO (-3607 3075);
FORCEPROP 2 LAST PATH I22
J 0
(-3275 3150);
DISPLAY 1.021277 (-3275 3150);
DISPLAY INVISIBLE (-3275 3150);
FORCEPROP 2 LAST CDS_LIB standard
J 0
(-3325 3075);
PAINT MONO (-3325 3075);
DISPLAY INVISIBLE (-3325 3075);
FORCEPROP 1 LAST OFFPAGE TRUE
J 0
(-3000 2950);
DISPLAY 0.872340 (-3000 2950);
PAINT GREEN (-3000 2950);
DISPLAY INVISIBLE (-3000 2950);
FORCEPROP 1 LAST COMMENT_BODY TRUE
J 0
(-3200 2975);
DISPLAY 0.872340 (-3200 2975);
PAINT GREEN (-3200 2975);
DISPLAY INVISIBLE (-3200 2975);
FORCEADD Q_RES..1
(-1625 2375);
FORCEPROP 1 LAST PART_NUMBER CS03322FB03
J 0
(-1750 2425);
DISPLAY 0.404255 (-1750 2425);
DISPLAY INVISIBLE (-1750 2425);
FORCEPROP 1 LAST TOLERANCE 1%
J 0
(-1450 2375);
DISPLAY 0.510638 (-1450 2375);
FORCEPROP 1 LAST VALUE 33.2
J 2
(-1475 2375);
DISPLAY 0.510638 (-1475 2375);
FORCEPROP 1 LAST PACK_TYPE 0402LF
J 0
(-1375 2375);
DISPLAY 0.510638 (-1375 2375);
FORCEPROP 1 LAST MATERIAL CHIP
J 0
(-1750 2450);
DISPLAY 0.404255 (-1750 2450);
FORCEPROP 1 LAST WATTAGE 1/16W
J 2
(-1525 2450);
DISPLAY 0.404255 (-1525 2450);
FORCEPROP 1 LAST $LOCATION R988
J 0
(-1850 2375);
DISPLAY 0.638298 (-1850 2375);
FORCEPROP 1 LASTPIN (-1725 2375) $PN 1
J 0
(-1713 2387);
DISPLAY 0.787234 (-1713 2387);
FORCEPROP 1 LASTPIN (-1525 2375) $PN 2
J 0
(-1563 2387);
DISPLAY 0.787234 (-1563 2387);
FORCEPROP 2 LAST CDS_LIB pure_quanta
J 0
(-1625 2375);
PAINT MONO (-1625 2375);
DISPLAY INVISIBLE (-1625 2375);
FORCEPROP 1 LAST PATH I23
J 0
(-1675 2525);
DISPLAY 0.978723 (-1675 2525);
PAINT WHITE (-1675 2525);
DISPLAY INVISIBLE (-1675 2525);
FORCEPROP 2 LAST CDS_LOCATION R988
J 0
(-1675 2575);
DISPLAY 1.021277 (-1675 2575);
DISPLAY INVISIBLE (-1675 2575);
FORCEPROP 2 LAST $SEC 1
J 0
(-1675 2575);
DISPLAY 0.680851 (-1675 2575);
PAINT MONO (-1675 2575);
DISPLAY INVISIBLE (-1675 2575);
FORCEPROP 2 LAST CDS_SEC 1
J 0
(-1675 2575);
DISPLAY 1.021277 (-1675 2575);
DISPLAY INVISIBLE (-1675 2575);
FORCEADD Q_RES..1
(-1625 2600);
FORCEPROP 1 LAST PART_NUMBER CS03322FB03
J 0
(-1750 2650);
DISPLAY 0.404255 (-1750 2650);
DISPLAY INVISIBLE (-1750 2650);
FORCEPROP 1 LAST TOLERANCE 1%
J 0
(-1450 2600);
DISPLAY 0.510638 (-1450 2600);
FORCEPROP 1 LAST VALUE 33.2
J 2
(-1475 2600);
DISPLAY 0.510638 (-1475 2600);
FORCEPROP 1 LAST MATERIAL CHIP
J 0
(-1750 2675);
DISPLAY 0.404255 (-1750 2675);
FORCEPROP 1 LAST WATTAGE 1/16W
J 2
(-1525 2675);
DISPLAY 0.404255 (-1525 2675);
FORCEPROP 1 LAST PACK_TYPE 0402LF
J 0
(-1375 2600);
DISPLAY 0.510638 (-1375 2600);
FORCEPROP 1 LAST $LOCATION R987
J 0
(-1850 2600);
DISPLAY 0.638298 (-1850 2600);
FORCEPROP 1 LASTPIN (-1725 2600) $PN 1
J 0
(-1713 2612);
DISPLAY 0.787234 (-1713 2612);
FORCEPROP 1 LASTPIN (-1525 2600) $PN 2
J 0
(-1563 2612);
DISPLAY 0.787234 (-1563 2612);
FORCEPROP 1 LAST PATH I24
J 0
(-1675 2750);
DISPLAY 0.978723 (-1675 2750);
PAINT WHITE (-1675 2750);
DISPLAY INVISIBLE (-1675 2750);
FORCEPROP 2 LAST CDS_LIB pure_quanta
J 0
(-1625 2600);
PAINT MONO (-1625 2600);
DISPLAY INVISIBLE (-1625 2600);
FORCEPROP 2 LAST CDS_LOCATION R987
J 0
(-1675 2800);
DISPLAY 1.021277 (-1675 2800);
DISPLAY INVISIBLE (-1675 2800);
FORCEPROP 2 LAST $SEC 1
J 0
(-1675 2800);
DISPLAY 0.680851 (-1675 2800);
PAINT MONO (-1675 2800);
DISPLAY INVISIBLE (-1675 2800);
FORCEPROP 2 LAST CDS_SEC 1
J 0
(-1675 2800);
DISPLAY 1.021277 (-1675 2800);
DISPLAY INVISIBLE (-1675 2800);
FORCEADD Q_RES..1
(-1625 2850);
FORCEPROP 1 LAST PART_NUMBER CS03322FB03
J 0
(-1750 2900);
DISPLAY 0.404255 (-1750 2900);
DISPLAY INVISIBLE (-1750 2900);
FORCEPROP 1 LAST TOLERANCE 1%
J 0
(-1450 2850);
DISPLAY 0.510638 (-1450 2850);
FORCEPROP 1 LAST VALUE 33.2
J 2
(-1475 2850);
DISPLAY 0.510638 (-1475 2850);
FORCEPROP 1 LAST MATERIAL CHIP
J 0
(-1750 2925);
DISPLAY 0.404255 (-1750 2925);
FORCEPROP 1 LAST PACK_TYPE 0402LF
J 0
(-1375 2850);
DISPLAY 0.510638 (-1375 2850);
FORCEPROP 1 LAST WATTAGE 1/16W
J 2
(-1525 2925);
DISPLAY 0.404255 (-1525 2925);
FORCEPROP 1 LAST $LOCATION R986
J 0
(-1850 2850);
DISPLAY 0.638298 (-1850 2850);
FORCEPROP 1 LASTPIN (-1725 2850) $PN 1
J 0
(-1713 2862);
DISPLAY 0.787234 (-1713 2862);
FORCEPROP 1 LASTPIN (-1525 2850) $PN 2
J 0
(-1563 2862);
DISPLAY 0.787234 (-1563 2862);
FORCEPROP 1 LAST PATH I25
J 0
(-1675 3000);
DISPLAY 0.978723 (-1675 3000);
PAINT WHITE (-1675 3000);
DISPLAY INVISIBLE (-1675 3000);
FORCEPROP 2 LAST CDS_LIB pure_quanta
J 0
(-1625 2850);
PAINT MONO (-1625 2850);
DISPLAY INVISIBLE (-1625 2850);
FORCEPROP 2 LAST CDS_LOCATION R986
J 0
(-1675 3050);
DISPLAY 1.021277 (-1675 3050);
DISPLAY INVISIBLE (-1675 3050);
FORCEPROP 2 LAST $SEC 1
J 0
(-1675 3050);
DISPLAY 0.680851 (-1675 3050);
PAINT MONO (-1675 3050);
DISPLAY INVISIBLE (-1675 3050);
FORCEPROP 2 LAST CDS_SEC 1
J 0
(-1675 3050);
DISPLAY 1.021277 (-1675 3050);
DISPLAY INVISIBLE (-1675 3050);
FORCEADD OFFPAGE..1
(-3325 2600);
FORCEPROP 2 LAST $XR1 219 
J 0
(-3727 2600);
DISPLAY 0.638298 (-3727 2600);
PAINT MONO (-3727 2600);
FORCEPROP 2 LAST $XR0 214 
J 0
(-3607 2600);
DISPLAY 0.638298 (-3607 2600);
PAINT MONO (-3607 2600);
FORCEPROP 2 LAST PATH I26
J 0
(-3275 2675);
DISPLAY 1.021277 (-3275 2675);
DISPLAY INVISIBLE (-3275 2675);
FORCEPROP 2 LAST CDS_LIB standard
J 0
(-3325 2600);
PAINT MONO (-3325 2600);
DISPLAY INVISIBLE (-3325 2600);
FORCEPROP 1 LAST OFFPAGE TRUE
J 0
(-3000 2475);
DISPLAY 0.872340 (-3000 2475);
PAINT GREEN (-3000 2475);
DISPLAY INVISIBLE (-3000 2475);
FORCEPROP 1 LAST COMMENT_BODY TRUE
J 0
(-3200 2500);
DISPLAY 0.872340 (-3200 2500);
PAINT GREEN (-3200 2500);
DISPLAY INVISIBLE (-3200 2500);
FORCEADD OFFPAGE..1
(-3325 2850);
FORCEPROP 2 LAST $XR1 219 
J 0
(-3727 2850);
DISPLAY 0.638298 (-3727 2850);
PAINT MONO (-3727 2850);
FORCEPROP 2 LAST $XR0 214 
J 0
(-3607 2850);
DISPLAY 0.638298 (-3607 2850);
PAINT MONO (-3607 2850);
FORCEPROP 2 LAST PATH I27
J 0
(-3275 2925);
DISPLAY 1.021277 (-3275 2925);
DISPLAY INVISIBLE (-3275 2925);
FORCEPROP 2 LAST CDS_LIB standard
J 0
(-3325 2850);
PAINT MONO (-3325 2850);
DISPLAY INVISIBLE (-3325 2850);
FORCEPROP 1 LAST OFFPAGE TRUE
J 0
(-3000 2725);
DISPLAY 0.872340 (-3000 2725);
PAINT GREEN (-3000 2725);
DISPLAY INVISIBLE (-3000 2725);
FORCEPROP 1 LAST COMMENT_BODY TRUE
J 0
(-3200 2750);
DISPLAY 0.872340 (-3200 2750);
PAINT GREEN (-3200 2750);
DISPLAY INVISIBLE (-3200 2750);
FORCEADD OFFPAGE..1
(-3325 2375);
FORCEPROP 2 LAST $XR1 219 
J 0
(-3727 2375);
DISPLAY 0.638298 (-3727 2375);
PAINT MONO (-3727 2375);
FORCEPROP 2 LAST $XR0 214 
J 0
(-3607 2375);
DISPLAY 0.638298 (-3607 2375);
PAINT MONO (-3607 2375);
FORCEPROP 1 LAST COMMENT_BODY TRUE
J 0
(-3200 2275);
DISPLAY 0.872340 (-3200 2275);
PAINT GREEN (-3200 2275);
DISPLAY INVISIBLE (-3200 2275);
FORCEPROP 1 LAST OFFPAGE TRUE
J 0
(-3000 2250);
DISPLAY 0.872340 (-3000 2250);
PAINT GREEN (-3000 2250);
DISPLAY INVISIBLE (-3000 2250);
FORCEPROP 2 LAST CDS_LIB standard
J 0
(-3325 2375);
PAINT MONO (-3325 2375);
DISPLAY INVISIBLE (-3325 2375);
FORCEPROP 2 LAST PATH I28
J 0
(-3275 2450);
DISPLAY 1.021277 (-3275 2450);
DISPLAY INVISIBLE (-3275 2450);
FORCEADD OFFPAGE..2
(325 4200);
FORCEPROP 2 LAST $XR0 266 
J 0
(514 4200);
DISPLAY 0.638298 (514 4200);
PAINT MONO (514 4200);
FORCEPROP 2 LAST PATH I3
J 0
(500 4275);
DISPLAY 1.021277 (500 4275);
DISPLAY INVISIBLE (500 4275);
FORCEPROP 2 LAST CDS_LIB standard
J 0
(325 4200);
PAINT MONO (325 4200);
DISPLAY INVISIBLE (325 4200);
FORCEPROP 1 LAST OFFPAGE TRUE
J 0
(650 4075);
DISPLAY 1.170213 (650 4075);
PAINT GREEN (650 4075);
DISPLAY INVISIBLE (650 4075);
FORCEPROP 1 LAST COMMENT_BODY TRUE
J 0
(280 4105);
DISPLAY 1.170213 (280 4105);
PAINT GREEN (280 4105);
DISPLAY INVISIBLE (280 4105);
FORCEADD OFFPAGE..1
(-3325 1725);
FORCEPROP 2 LAST $XR2 255 
J 0
(-3847 1725);
DISPLAY 0.638298 (-3847 1725);
PAINT MONO (-3847 1725);
FORCEPROP 2 LAST $XR1 220 
J 0
(-3727 1725);
DISPLAY 0.638298 (-3727 1725);
PAINT MONO (-3727 1725);
FORCEPROP 2 LAST $XR0 214 
J 0
(-3607 1725);
DISPLAY 0.638298 (-3607 1725);
PAINT MONO (-3607 1725);
FORCEPROP 2 LAST PATH I42
J 0
(-3600 1775);
DISPLAY 1.021277 (-3600 1775);
DISPLAY INVISIBLE (-3600 1775);
FORCEPROP 2 LAST CDS_LIB standard
J 0
(-3325 1725);
PAINT MONO (-3325 1725);
DISPLAY INVISIBLE (-3325 1725);
FORCEPROP 1 LAST OFFPAGE TRUE
J 0
(-3000 1600);
DISPLAY 0.872340 (-3000 1600);
PAINT GREEN (-3000 1600);
DISPLAY INVISIBLE (-3000 1600);
FORCEPROP 1 LAST COMMENT_BODY TRUE
J 0
(-3200 1625);
DISPLAY 0.872340 (-3200 1625);
PAINT GREEN (-3200 1625);
DISPLAY INVISIBLE (-3200 1625);
FORCEADD OFFPAGE..2
(325 1725);
FORCEPROP 2 LAST $XR2 240 
J 0
(754 1725);
DISPLAY 0.638298 (754 1725);
PAINT MONO (754 1725);
FORCEPROP 2 LAST $XR1 219 
J 0
(634 1725);
DISPLAY 0.638298 (634 1725);
PAINT MONO (634 1725);
FORCEPROP 2 LAST $XR0 182 
J 0
(514 1725);
DISPLAY 0.638298 (514 1725);
PAINT MONO (514 1725);
FORCEPROP 2 LAST PATH I43
J 0
(675 1775);
DISPLAY 1.021277 (675 1775);
DISPLAY INVISIBLE (675 1775);
FORCEPROP 2 LAST CDS_LIB standard
J 0
(325 1725);
PAINT MONO (325 1725);
DISPLAY INVISIBLE (325 1725);
FORCEPROP 1 LAST OFFPAGE TRUE
J 0
(650 1600);
DISPLAY 1.170213 (650 1600);
PAINT GREEN (650 1600);
DISPLAY INVISIBLE (650 1600);
FORCEPROP 1 LAST COMMENT_BODY TRUE
J 0
(280 1630);
DISPLAY 1.170213 (280 1630);
PAINT GREEN (280 1630);
DISPLAY INVISIBLE (280 1630);
FORCEADD Q_RES..1
(-1625 1725);
FORCEPROP 1 LAST PART_NUMBER CS03322FB03
J 0
(-1725 1800);
DISPLAY 0.510638 (-1725 1800);
DISPLAY INVISIBLE (-1725 1800);
FORCEPROP 1 LAST WATTAGE 1/16W
J 2
(-1450 1850);
DISPLAY 0.510638 (-1450 1850);
FORCEPROP 1 LAST VALUE 33.2
J 2
(-1425 1725);
DISPLAY 0.510638 (-1425 1725);
FORCEPROP 1 LAST PACK_TYPE 0402LF
J 0
(-1325 1725);
DISPLAY 0.510638 (-1325 1725);
FORCEPROP 1 LAST MATERIAL CHIP
J 0
(-1725 1850);
DISPLAY 0.510638 (-1725 1850);
FORCEPROP 1 LAST TOLERANCE 1%
J 0
(-1400 1725);
DISPLAY 0.510638 (-1400 1725);
FORCEPROP 1 LAST $LOCATION R1423
J 0
(-1875 1725);
DISPLAY 0.638298 (-1875 1725);
FORCEPROP 1 LASTPIN (-1725 1725) $PN 1
J 0
(-1713 1737);
DISPLAY 0.787234 (-1713 1737);
FORCEPROP 1 LASTPIN (-1525 1725) $PN 2
J 0
(-1563 1737);
DISPLAY 0.787234 (-1563 1737);
FORCEPROP 1 LAST PATH I44
J 0
(-1675 1875);
DISPLAY 0.978723 (-1675 1875);
PAINT WHITE (-1675 1875);
DISPLAY INVISIBLE (-1675 1875);
FORCEPROP 2 LAST CDS_LIB pure_quanta
J 0
(-1625 1725);
PAINT MONO (-1625 1725);
DISPLAY INVISIBLE (-1625 1725);
FORCEPROP 2 LAST CDS_LOCATION R1423
J 0
(-1675 1925);
DISPLAY 1.021277 (-1675 1925);
DISPLAY INVISIBLE (-1675 1925);
FORCEPROP 2 LAST $SEC 1
J 0
(-1675 1925);
DISPLAY 0.680851 (-1675 1925);
PAINT MONO (-1675 1925);
DISPLAY INVISIBLE (-1675 1925);
FORCEPROP 2 LAST CDS_SEC 1
J 0
(-1675 1925);
DISPLAY 1.021277 (-1675 1925);
DISPLAY INVISIBLE (-1675 1925);
FORCEADD OFFPAGE..2
(325 1500);
FORCEPROP 2 LAST $XR1 219 
J 0
(634 1500);
DISPLAY 0.638298 (634 1500);
PAINT MONO (634 1500);
FORCEPROP 2 LAST $XR0 182 
J 0
(514 1500);
DISPLAY 0.638298 (514 1500);
PAINT MONO (514 1500);
FORCEPROP 2 LAST PATH I45
J 0
(525 1550);
DISPLAY 1.021277 (525 1550);
DISPLAY INVISIBLE (525 1550);
FORCEPROP 2 LAST CDS_LIB standard
J 0
(325 1500);
PAINT MONO (325 1500);
DISPLAY INVISIBLE (325 1500);
FORCEPROP 1 LAST OFFPAGE TRUE
J 0
(650 1375);
DISPLAY 1.170213 (650 1375);
PAINT GREEN (650 1375);
DISPLAY INVISIBLE (650 1375);
FORCEPROP 1 LAST COMMENT_BODY TRUE
J 0
(280 1405);
DISPLAY 1.170213 (280 1405);
PAINT GREEN (280 1405);
DISPLAY INVISIBLE (280 1405);
FORCEADD OFFPAGE..1
(-3325 1500);
FORCEPROP 2 LAST $XR2 255 
J 0
(-3847 1500);
DISPLAY 0.638298 (-3847 1500);
PAINT MONO (-3847 1500);
FORCEPROP 2 LAST $XR1 220 
J 0
(-3727 1500);
DISPLAY 0.638298 (-3727 1500);
PAINT MONO (-3727 1500);
FORCEPROP 2 LAST $XR0 214 
J 0
(-3607 1500);
DISPLAY 0.638298 (-3607 1500);
PAINT MONO (-3607 1500);
FORCEPROP 2 LAST PATH I47
J 0
(-3625 1550);
DISPLAY 1.021277 (-3625 1550);
DISPLAY INVISIBLE (-3625 1550);
FORCEPROP 2 LAST CDS_LIB standard
J 0
(-3325 1500);
PAINT MONO (-3325 1500);
DISPLAY INVISIBLE (-3325 1500);
FORCEPROP 1 LAST OFFPAGE TRUE
J 0
(-3000 1375);
DISPLAY 0.872340 (-3000 1375);
PAINT GREEN (-3000 1375);
DISPLAY INVISIBLE (-3000 1375);
FORCEPROP 1 LAST COMMENT_BODY TRUE
J 0
(-3200 1400);
DISPLAY 0.872340 (-3200 1400);
PAINT GREEN (-3200 1400);
DISPLAY INVISIBLE (-3200 1400);
FORCEADD Q_RES..1
(-1625 1500);
FORCEPROP 1 LAST PART_NUMBER CS03322FB03
J 0
(-1725 1575);
DISPLAY 0.510638 (-1725 1575);
DISPLAY INVISIBLE (-1725 1575);
FORCEPROP 1 LAST PACK_TYPE 0402LF
J 0
(-1325 1500);
DISPLAY 0.510638 (-1325 1500);
FORCEPROP 1 LAST MATERIAL CHIP
J 0
(-1725 1625);
DISPLAY 0.510638 (-1725 1625);
FORCEPROP 1 LAST WATTAGE 1/16W
J 2
(-1450 1625);
DISPLAY 0.510638 (-1450 1625);
FORCEPROP 1 LAST VALUE 33.2
J 2
(-1425 1500);
DISPLAY 0.510638 (-1425 1500);
FORCEPROP 1 LAST TOLERANCE 1%
J 0
(-1400 1500);
DISPLAY 0.510638 (-1400 1500);
FORCEPROP 1 LAST $LOCATION R1442
J 0
(-1875 1500);
DISPLAY 0.787234 (-1875 1500);
FORCEPROP 1 LASTPIN (-1725 1500) $PN 1
J 0
(-1713 1512);
DISPLAY 0.787234 (-1713 1512);
FORCEPROP 1 LASTPIN (-1525 1500) $PN 2
J 0
(-1563 1512);
DISPLAY 0.787234 (-1563 1512);
FORCEPROP 1 LAST PATH I48
J 0
(-1675 1650);
DISPLAY 0.978723 (-1675 1650);
PAINT WHITE (-1675 1650);
DISPLAY INVISIBLE (-1675 1650);
FORCEPROP 2 LAST CDS_LIB pure_quanta
J 0
(-1625 1500);
PAINT MONO (-1625 1500);
DISPLAY INVISIBLE (-1625 1500);
FORCEPROP 2 LAST CDS_LOCATION R1442
J 0
(-1675 1700);
DISPLAY 1.021277 (-1675 1700);
DISPLAY INVISIBLE (-1675 1700);
FORCEPROP 2 LAST $SEC 1
J 0
(-1675 1700);
DISPLAY 0.680851 (-1675 1700);
PAINT MONO (-1675 1700);
DISPLAY INVISIBLE (-1675 1700);
FORCEPROP 2 LAST CDS_SEC 1
J 0
(-1675 1700);
DISPLAY 1.021277 (-1675 1700);
DISPLAY INVISIBLE (-1675 1700);
FORCEADD Q_RES..1
(-1625 1250);
FORCEPROP 1 LAST PART_NUMBER CS03322FB03
J 0
(-1725 1325);
DISPLAY 0.510638 (-1725 1325);
DISPLAY INVISIBLE (-1725 1325);
FORCEPROP 1 LAST TOLERANCE 1%
J 0
(-1400 1250);
DISPLAY 0.510638 (-1400 1250);
FORCEPROP 1 LAST PACK_TYPE 0402LF
J 0
(-1325 1250);
DISPLAY 0.510638 (-1325 1250);
FORCEPROP 1 LAST MATERIAL CHIP
J 0
(-1725 1375);
DISPLAY 0.510638 (-1725 1375);
FORCEPROP 1 LAST WATTAGE 1/16W
J 2
(-1450 1375);
DISPLAY 0.510638 (-1450 1375);
FORCEPROP 1 LAST VALUE 33.2
J 2
(-1425 1250);
DISPLAY 0.510638 (-1425 1250);
FORCEPROP 1 LAST $LOCATION R1443
J 0
(-1875 1250);
DISPLAY 0.787234 (-1875 1250);
FORCEPROP 1 LASTPIN (-1725 1250) $PN 1
J 0
(-1713 1262);
DISPLAY 0.787234 (-1713 1262);
FORCEPROP 1 LASTPIN (-1525 1250) $PN 2
J 0
(-1563 1262);
DISPLAY 0.787234 (-1563 1262);
FORCEPROP 2 LAST CDS_LIB pure_quanta
J 0
(-1625 1250);
PAINT MONO (-1625 1250);
DISPLAY INVISIBLE (-1625 1250);
FORCEPROP 1 LAST PATH I49
J 0
(-1675 1400);
DISPLAY 0.978723 (-1675 1400);
PAINT WHITE (-1675 1400);
DISPLAY INVISIBLE (-1675 1400);
FORCEPROP 2 LAST CDS_LOCATION R1443
J 0
(-1675 1450);
DISPLAY 1.021277 (-1675 1450);
DISPLAY INVISIBLE (-1675 1450);
FORCEPROP 2 LAST $SEC 1
J 0
(-1675 1450);
DISPLAY 0.680851 (-1675 1450);
PAINT MONO (-1675 1450);
DISPLAY INVISIBLE (-1675 1450);
FORCEPROP 2 LAST CDS_SEC 1
J 0
(-1675 1450);
DISPLAY 1.021277 (-1675 1450);
DISPLAY INVISIBLE (-1675 1450);
FORCEADD OFFPAGE..5
(-3325 1250);
FORCEPROP 2 LAST $XR0 226 
J 0
(-3580 1250);
DISPLAY 0.638298 (-3580 1250);
PAINT MONO (-3580 1250);
FORCEPROP 2 LAST CDS_LIB standard
J 0
(-3325 1250);
PAINT MONO (-3325 1250);
DISPLAY INVISIBLE (-3325 1250);
FORCEPROP 1 LAST OFFPAGE TRUE
J 0
(-3000 1125);
DISPLAY 0.872340 (-3000 1125);
PAINT GREEN (-3000 1125);
DISPLAY INVISIBLE (-3000 1125);
FORCEPROP 1 LAST COMMENT_BODY TRUE
J 0
(-3225 1175);
DISPLAY 0.872340 (-3225 1175);
PAINT PEACH (-3225 1175);
DISPLAY INVISIBLE (-3225 1175);
FORCEPROP 2 LAST PATH I50
J 0
(-3625 1300);
DISPLAY 1.021277 (-3625 1300);
DISPLAY INVISIBLE (-3625 1300);
FORCEADD OFFPAGE..4
(350 1250);
FORCEPROP 2 LAST $XR0 118 
J 0
(536 1250);
DISPLAY 0.638298 (536 1250);
PAINT MONO (536 1250);
FORCEPROP 1 LAST COMMENT_BODY TRUE
J 0
(325 1150);
DISPLAY 0.872340 (325 1150);
PAINT PEACH (325 1150);
DISPLAY INVISIBLE (325 1150);
FORCEPROP 1 LAST OFFPAGE TRUE
J 0
(675 1125);
DISPLAY 0.872340 (675 1125);
PAINT GREEN (675 1125);
DISPLAY INVISIBLE (675 1125);
FORCEPROP 2 LAST CDS_LIB standard
J 0
(350 1250);
PAINT MONO (350 1250);
DISPLAY INVISIBLE (350 1250);
FORCEPROP 2 LAST PATH I51
J 0
(550 1300);
DISPLAY 1.021277 (550 1300);
DISPLAY INVISIBLE (550 1300);
FORCEADD OFFPAGE..1
(-3325 1025);
FORCEPROP 2 LAST $XR2 252 
J 0
(-3847 1025);
DISPLAY 0.638298 (-3847 1025);
PAINT MONO (-3847 1025);
FORCEPROP 2 LAST $XR1 194 
J 0
(-3727 1025);
DISPLAY 0.638298 (-3727 1025);
PAINT MONO (-3727 1025);
FORCEPROP 2 LAST $XR0 263 
J 0
(-3607 1025);
DISPLAY 0.638298 (-3607 1025);
PAINT MONO (-3607 1025);
FORCEPROP 2 LAST PATH I52
J 0
(-3625 1075);
DISPLAY 1.021277 (-3625 1075);
DISPLAY INVISIBLE (-3625 1075);
FORCEPROP 2 LAST CDS_LIB standard
J 0
(-3325 1025);
PAINT MONO (-3325 1025);
DISPLAY INVISIBLE (-3325 1025);
FORCEPROP 1 LAST OFFPAGE TRUE
J 0
(-3000 900);
DISPLAY 0.872340 (-3000 900);
PAINT GREEN (-3000 900);
DISPLAY INVISIBLE (-3000 900);
FORCEPROP 1 LAST COMMENT_BODY TRUE
J 0
(-3200 925);
DISPLAY 0.872340 (-3200 925);
PAINT GREEN (-3200 925);
DISPLAY INVISIBLE (-3200 925);
FORCEADD OFFPAGE..2
(325 1025);
FORCEPROP 2 LAST $XR0 214 
J 0
(514 1025);
DISPLAY 0.638298 (514 1025);
PAINT MONO (514 1025);
FORCEPROP 2 LAST PATH I53
J 0
(525 1075);
DISPLAY 1.021277 (525 1075);
DISPLAY INVISIBLE (525 1075);
FORCEPROP 2 LAST CDS_LIB standard
J 0
(325 1025);
PAINT MONO (325 1025);
DISPLAY INVISIBLE (325 1025);
FORCEPROP 1 LAST OFFPAGE TRUE
J 0
(650 900);
DISPLAY 1.170213 (650 900);
PAINT GREEN (650 900);
DISPLAY INVISIBLE (650 900);
FORCEPROP 1 LAST COMMENT_BODY TRUE
J 0
(280 930);
DISPLAY 1.170213 (280 930);
PAINT GREEN (280 930);
DISPLAY INVISIBLE (280 930);
FORCEADD Q_RES..1
(-1625 1025);
FORCEPROP 1 LAST PART_NUMBER CS03322FB03
J 0
(-1725 1100);
DISPLAY 0.510638 (-1725 1100);
DISPLAY INVISIBLE (-1725 1100);
FORCEPROP 1 LAST WATTAGE 1/16W
J 2
(-1450 1150);
DISPLAY 0.510638 (-1450 1150);
FORCEPROP 1 LAST MATERIAL CHIP
J 0
(-1725 1150);
DISPLAY 0.510638 (-1725 1150);
FORCEPROP 1 LAST VALUE 33.2
J 2
(-1425 1025);
DISPLAY 0.510638 (-1425 1025);
FORCEPROP 1 LAST TOLERANCE 1%
J 0
(-1400 1025);
DISPLAY 0.510638 (-1400 1025);
FORCEPROP 1 LAST PACK_TYPE 0402LF
J 0
(-1325 1025);
DISPLAY 0.510638 (-1325 1025);
FORCEPROP 1 LAST $LOCATION R1444
J 0
(-1875 1025);
DISPLAY 0.787234 (-1875 1025);
FORCEPROP 1 LASTPIN (-1725 1025) $PN 1
J 0
(-1713 1037);
DISPLAY 0.787234 (-1713 1037);
FORCEPROP 1 LASTPIN (-1525 1025) $PN 2
J 0
(-1563 1037);
DISPLAY 0.787234 (-1563 1037);
FORCEPROP 1 LAST PATH I54
J 0
(-1675 1175);
DISPLAY 0.978723 (-1675 1175);
PAINT WHITE (-1675 1175);
DISPLAY INVISIBLE (-1675 1175);
FORCEPROP 2 LAST CDS_LIB pure_quanta
J 0
(-1625 1025);
PAINT MONO (-1625 1025);
DISPLAY INVISIBLE (-1625 1025);
FORCEPROP 2 LAST CDS_LOCATION R1444
J 0
(-1675 1225);
DISPLAY 1.021277 (-1675 1225);
DISPLAY INVISIBLE (-1675 1225);
FORCEPROP 2 LAST $SEC 1
J 0
(-1675 1225);
DISPLAY 0.680851 (-1675 1225);
PAINT MONO (-1675 1225);
DISPLAY INVISIBLE (-1675 1225);
FORCEPROP 2 LAST CDS_SEC 1
J 0
(-1675 1225);
DISPLAY 1.021277 (-1675 1225);
DISPLAY INVISIBLE (-1675 1225);
FORCEADD OFFPAGE..1
(-3325 3975);
FORCEPROP 2 LAST $XR1 219 
J 0
(-3727 3975);
DISPLAY 0.638298 (-3727 3975);
PAINT MONO (-3727 3975);
FORCEPROP 2 LAST $XR0 214 
J 0
(-3607 3975);
DISPLAY 0.638298 (-3607 3975);
PAINT MONO (-3607 3975);
FORCEPROP 2 LAST PATH I6
J 0
(-3600 4025);
DISPLAY 1.021277 (-3600 4025);
DISPLAY INVISIBLE (-3600 4025);
FORCEPROP 2 LAST CDS_LIB standard
J 0
(-3325 3975);
PAINT MONO (-3325 3975);
DISPLAY INVISIBLE (-3325 3975);
FORCEPROP 1 LAST OFFPAGE TRUE
J 0
(-3000 3850);
DISPLAY 0.872340 (-3000 3850);
PAINT GREEN (-3000 3850);
DISPLAY INVISIBLE (-3000 3850);
FORCEPROP 1 LAST COMMENT_BODY TRUE
J 0
(-3200 3875);
DISPLAY 0.872340 (-3200 3875);
PAINT GREEN (-3200 3875);
DISPLAY INVISIBLE (-3200 3875);
FORCEADD Q_RES..1
(-1625 -600);
FORCEPROP 1 LAST PART_NUMBER CS03322FB03
J 0
(-1725 -525);
DISPLAY 0.510638 (-1725 -525);
DISPLAY INVISIBLE (-1725 -525);
FORCEPROP 1 LAST WATTAGE 1/16W
J 2
(-1450 -475);
DISPLAY 0.510638 (-1450 -475);
FORCEPROP 1 LAST VALUE 33.2
J 2
(-1425 -600);
DISPLAY 0.510638 (-1425 -600);
FORCEPROP 1 LAST TOLERANCE 1%
J 0
(-1400 -600);
DISPLAY 0.510638 (-1400 -600);
FORCEPROP 1 LAST PACK_TYPE 0402LF
J 0
(-1325 -600);
DISPLAY 0.510638 (-1325 -600);
FORCEPROP 1 LAST MATERIAL CHIP
J 0
(-1725 -475);
DISPLAY 0.510638 (-1725 -475);
FORCEPROP 1 LAST $LOCATION R1448
J 0
(-1875 -600);
DISPLAY 0.787234 (-1875 -600);
FORCEPROP 1 LASTPIN (-1725 -600) $PN 1
J 0
(-1713 -588);
DISPLAY 0.787234 (-1713 -588);
FORCEPROP 1 LASTPIN (-1525 -600) $PN 2
J 0
(-1563 -588);
DISPLAY 0.787234 (-1563 -588);
FORCEPROP 1 LAST PATH I62
J 0
(-1675 -450);
DISPLAY 0.978723 (-1675 -450);
PAINT WHITE (-1675 -450);
DISPLAY INVISIBLE (-1675 -450);
FORCEPROP 2 LAST CDS_LIB pure_quanta
J 0
(-1625 -600);
PAINT MONO (-1625 -600);
DISPLAY INVISIBLE (-1625 -600);
FORCEPROP 2 LAST CDS_LOCATION R1448
J 0
(-1675 -400);
DISPLAY 1.021277 (-1675 -400);
DISPLAY INVISIBLE (-1675 -400);
FORCEPROP 2 LAST $SEC 1
J 0
(-1675 -400);
DISPLAY 0.680851 (-1675 -400);
PAINT MONO (-1675 -400);
DISPLAY INVISIBLE (-1675 -400);
FORCEPROP 2 LAST CDS_SEC 1
J 0
(-1675 -400);
DISPLAY 1.021277 (-1675 -400);
DISPLAY INVISIBLE (-1675 -400);
FORCEADD OFFPAGE..2
(325 -375);
FORCEPROP 2 LAST $XR0 214 
J 0
(514 -375);
DISPLAY 0.638298 (514 -375);
PAINT MONO (514 -375);
FORCEPROP 2 LAST PATH I63
J 0
(525 -325);
DISPLAY 1.021277 (525 -325);
DISPLAY INVISIBLE (525 -325);
FORCEPROP 2 LAST CDS_LIB standard
J 0
(325 -375);
PAINT MONO (325 -375);
DISPLAY INVISIBLE (325 -375);
FORCEPROP 1 LAST OFFPAGE TRUE
J 0
(650 -500);
DISPLAY 1.170213 (650 -500);
PAINT GREEN (650 -500);
DISPLAY INVISIBLE (650 -500);
FORCEPROP 1 LAST COMMENT_BODY TRUE
J 0
(280 -470);
DISPLAY 1.170213 (280 -470);
PAINT GREEN (280 -470);
DISPLAY INVISIBLE (280 -470);
FORCEADD OFFPAGE..2
(325 -600);
FORCEPROP 2 LAST $XR0 214 
J 0
(514 -600);
DISPLAY 0.638298 (514 -600);
PAINT MONO (514 -600);
FORCEPROP 2 LAST PATH I64
J 0
(525 -550);
DISPLAY 1.021277 (525 -550);
DISPLAY INVISIBLE (525 -550);
FORCEPROP 2 LAST CDS_LIB standard
J 0
(325 -600);
PAINT MONO (325 -600);
DISPLAY INVISIBLE (325 -600);
FORCEPROP 1 LAST OFFPAGE TRUE
J 0
(650 -725);
DISPLAY 1.170213 (650 -725);
PAINT GREEN (650 -725);
DISPLAY INVISIBLE (650 -725);
FORCEPROP 1 LAST COMMENT_BODY TRUE
J 0
(280 -695);
DISPLAY 1.170213 (280 -695);
PAINT GREEN (280 -695);
DISPLAY INVISIBLE (280 -695);
FORCEADD OFFPAGE..1
(-3325 -375);
FORCEPROP 2 LAST $XR1 133 
J 0
(-3696 -375);
DISPLAY 0.638298 (-3696 -375);
PAINT MONO (-3696 -375);
FORCEPROP 2 LAST $XR0 14 
J 0
(-3576 -375);
DISPLAY 0.638298 (-3576 -375);
PAINT MONO (-3576 -375);
FORCEPROP 2 LAST PATH I66
J 0
(-3625 -325);
DISPLAY 1.021277 (-3625 -325);
DISPLAY INVISIBLE (-3625 -325);
FORCEPROP 2 LAST CDS_LIB standard
J 0
(-3325 -375);
PAINT MONO (-3325 -375);
DISPLAY INVISIBLE (-3325 -375);
FORCEPROP 1 LAST OFFPAGE TRUE
J 0
(-3000 -500);
DISPLAY 0.872340 (-3000 -500);
PAINT GREEN (-3000 -500);
DISPLAY INVISIBLE (-3000 -500);
FORCEPROP 1 LAST COMMENT_BODY TRUE
J 0
(-3200 -475);
DISPLAY 0.872340 (-3200 -475);
PAINT GREEN (-3200 -475);
DISPLAY INVISIBLE (-3200 -475);
FORCEADD OFFPAGE..1
(-3325 -600);
FORCEPROP 2 LAST $XR1 133 
J 0
(-3696 -600);
DISPLAY 0.638298 (-3696 -600);
PAINT MONO (-3696 -600);
FORCEPROP 2 LAST $XR0 45 
J 0
(-3576 -600);
DISPLAY 0.638298 (-3576 -600);
PAINT MONO (-3576 -600);
FORCEPROP 2 LAST PATH I67
J 0
(-3625 -550);
DISPLAY 1.021277 (-3625 -550);
DISPLAY INVISIBLE (-3625 -550);
FORCEPROP 2 LAST CDS_LIB standard
J 0
(-3325 -600);
PAINT MONO (-3325 -600);
DISPLAY INVISIBLE (-3325 -600);
FORCEPROP 1 LAST OFFPAGE TRUE
J 0
(-3000 -725);
DISPLAY 0.872340 (-3000 -725);
PAINT GREEN (-3000 -725);
DISPLAY INVISIBLE (-3000 -725);
FORCEPROP 1 LAST COMMENT_BODY TRUE
J 0
(-3200 -700);
DISPLAY 0.872340 (-3200 -700);
PAINT GREEN (-3200 -700);
DISPLAY INVISIBLE (-3200 -700);
FORCEADD Q_RES..1
(-1625 -375);
FORCEPROP 1 LAST PART_NUMBER CS03322FB03
J 0
(-1725 -300);
DISPLAY 0.510638 (-1725 -300);
DISPLAY INVISIBLE (-1725 -300);
FORCEPROP 1 LAST VALUE 33.2
J 2
(-1425 -375);
DISPLAY 0.510638 (-1425 -375);
FORCEPROP 1 LAST TOLERANCE 1%
J 0
(-1400 -375);
DISPLAY 0.510638 (-1400 -375);
FORCEPROP 1 LAST PACK_TYPE 0402LF
J 0
(-1325 -375);
DISPLAY 0.510638 (-1325 -375);
FORCEPROP 1 LAST MATERIAL CHIP
J 0
(-1725 -250);
DISPLAY 0.510638 (-1725 -250);
FORCEPROP 1 LAST WATTAGE 1/16W
J 2
(-1450 -250);
DISPLAY 0.510638 (-1450 -250);
FORCEPROP 1 LAST $LOCATION R1447
J 0
(-1875 -375);
DISPLAY 0.787234 (-1875 -375);
FORCEPROP 1 LASTPIN (-1725 -375) $PN 1
J 0
(-1713 -363);
DISPLAY 0.787234 (-1713 -363);
FORCEPROP 1 LASTPIN (-1525 -375) $PN 2
J 0
(-1563 -363);
DISPLAY 0.787234 (-1563 -363);
FORCEPROP 1 LAST PATH I68
J 0
(-1675 -225);
DISPLAY 0.978723 (-1675 -225);
PAINT WHITE (-1675 -225);
DISPLAY INVISIBLE (-1675 -225);
FORCEPROP 2 LAST CDS_LIB pure_quanta
J 0
(-1625 -375);
PAINT MONO (-1625 -375);
DISPLAY INVISIBLE (-1625 -375);
FORCEPROP 2 LAST CDS_LOCATION R1447
J 0
(-1675 -175);
DISPLAY 1.021277 (-1675 -175);
DISPLAY INVISIBLE (-1675 -175);
FORCEPROP 2 LAST $SEC 1
J 0
(-1675 -175);
DISPLAY 0.680851 (-1675 -175);
PAINT MONO (-1675 -175);
DISPLAY INVISIBLE (-1675 -175);
FORCEPROP 2 LAST CDS_SEC 1
J 0
(-1675 -175);
DISPLAY 1.021277 (-1675 -175);
DISPLAY INVISIBLE (-1675 -175);
FORCEADD OFFPAGE..2
(325 3975);
FORCEPROP 2 LAST $XR0 274 
J 0
(514 3975);
DISPLAY 0.638298 (514 3975);
PAINT MONO (514 3975);
FORCEPROP 2 LAST PATH I7
J 0
(500 4050);
DISPLAY 1.021277 (500 4050);
DISPLAY INVISIBLE (500 4050);
FORCEPROP 2 LAST CDS_LIB standard
J 0
(325 3975);
PAINT MONO (325 3975);
DISPLAY INVISIBLE (325 3975);
FORCEPROP 1 LAST OFFPAGE TRUE
J 0
(650 3850);
DISPLAY 1.170213 (650 3850);
PAINT GREEN (650 3850);
DISPLAY INVISIBLE (650 3850);
FORCEPROP 1 LAST COMMENT_BODY TRUE
J 0
(280 3880);
DISPLAY 1.170213 (280 3880);
PAINT GREEN (280 3880);
DISPLAY INVISIBLE (280 3880);
FORCEADD OFFPAGE..2
(4500 3975);
FORCEPROP 2 LAST $XR0 213 
J 0
(4689 3975);
DISPLAY 0.638298 (4689 3975);
PAINT MONO (4689 3975);
FORCEPROP 2 LAST CDS_LIB standard
J 0
(4500 3975);
PAINT MONO (4500 3975);
DISPLAY INVISIBLE (4500 3975);
FORCEPROP 1 LAST OFFPAGE TRUE
J 0
(4825 3850);
DISPLAY 1.170213 (4825 3850);
PAINT GREEN (4825 3850);
DISPLAY INVISIBLE (4825 3850);
FORCEPROP 1 LAST COMMENT_BODY TRUE
J 0
(4455 3880);
DISPLAY 1.170213 (4455 3880);
PAINT GREEN (4455 3880);
DISPLAY INVISIBLE (4455 3880);
FORCEPROP 2 LAST PATH I77
J 0
(4700 4025);
DISPLAY 1.021277 (4700 4025);
DISPLAY INVISIBLE (4700 4025);
FORCEADD OFFPAGE..1
(1625 3975);
FORCEPROP 2 LAST $XR0 240 
J 0
(1343 3975);
DISPLAY 0.638298 (1343 3975);
PAINT MONO (1343 3975);
FORCEPROP 1 LAST COMMENT_BODY TRUE
J 0
(1750 3875);
DISPLAY 0.872340 (1750 3875);
PAINT GREEN (1750 3875);
DISPLAY INVISIBLE (1750 3875);
FORCEPROP 1 LAST OFFPAGE TRUE
J 0
(1950 3850);
DISPLAY 0.872340 (1950 3850);
PAINT GREEN (1950 3850);
DISPLAY INVISIBLE (1950 3850);
FORCEPROP 2 LAST CDS_LIB standard
J 0
(1625 3975);
PAINT MONO (1625 3975);
DISPLAY INVISIBLE (1625 3975);
FORCEPROP 2 LAST PATH I80
J 0
(1375 4025);
DISPLAY 1.021277 (1375 4025);
DISPLAY INVISIBLE (1375 4025);
FORCEADD Q_RES..1
(3000 4200);
FORCEPROP 1 LAST PART_NUMBER CS03322FB03
J 0
(2900 4275);
DISPLAY 0.404255 (2900 4275);
DISPLAY INVISIBLE (2900 4275);
FORCEPROP 1 LAST MATERIAL CHIP
J 0
(3250 4200);
DISPLAY 0.404255 (3250 4200);
FORCEPROP 1 LAST TOLERANCE 1%
J 0
(3200 4200);
DISPLAY 0.404255 (3200 4200);
FORCEPROP 1 LAST VALUE 33.2
J 2
(3175 4200);
DISPLAY 0.404255 (3175 4200);
FORCEPROP 1 LAST WATTAGE 1/16W
J 2
(3125 4300);
DISPLAY 0.404255 (3125 4300);
FORCEPROP 1 LAST PACK_TYPE 0402LF
J 0
(2900 4300);
DISPLAY 0.404255 (2900 4300);
FORCEPROP 1 LAST $LOCATION R1751
J 0
(2750 4200);
DISPLAY 0.638298 (2750 4200);
FORCEPROP 1 LASTPIN (2900 4200) $PN 1
J 0
(2912 4212);
DISPLAY 0.787234 (2912 4212);
FORCEPROP 1 LASTPIN (3100 4200) $PN 2
J 0
(3062 4212);
DISPLAY 0.787234 (3062 4212);
FORCEPROP 2 LAST CDS_LIB pure_quanta
J 0
(3000 4200);
PAINT MONO (3000 4200);
DISPLAY INVISIBLE (3000 4200);
FORCEPROP 1 LAST PATH I81
J 0
(2950 4350);
DISPLAY 0.978723 (2950 4350);
PAINT WHITE (2950 4350);
DISPLAY INVISIBLE (2950 4350);
FORCEPROP 2 LAST CDS_LOCATION R1751
J 0
(2950 4400);
DISPLAY 1.021277 (2950 4400);
DISPLAY INVISIBLE (2950 4400);
FORCEPROP 2 LAST $SEC 1
J 0
(2950 4400);
DISPLAY 0.680851 (2950 4400);
PAINT MONO (2950 4400);
DISPLAY INVISIBLE (2950 4400);
FORCEPROP 2 LAST CDS_SEC 1
J 0
(2950 4400);
DISPLAY 1.021277 (2950 4400);
DISPLAY INVISIBLE (2950 4400);
FORCEADD Q_RES..1
(3000 3975);
FORCEPROP 1 LAST PART_NUMBER CS03322FB03
J 0
(2900 4050);
DISPLAY 0.404255 (2900 4050);
DISPLAY INVISIBLE (2900 4050);
FORCEPROP 1 LAST MATERIAL CHIP
J 0
(3250 3975);
DISPLAY 0.404255 (3250 3975);
FORCEPROP 1 LAST TOLERANCE 1%
J 0
(3200 3975);
DISPLAY 0.404255 (3200 3975);
FORCEPROP 1 LAST VALUE 33.2
J 2
(3175 3975);
DISPLAY 0.404255 (3175 3975);
FORCEPROP 1 LAST WATTAGE 1/16W
J 2
(3125 4075);
DISPLAY 0.404255 (3125 4075);
FORCEPROP 1 LAST PACK_TYPE 0402LF
J 0
(2900 4075);
DISPLAY 0.404255 (2900 4075);
FORCEPROP 1 LAST $LOCATION R1752
J 0
(2750 3975);
DISPLAY 0.638298 (2750 3975);
FORCEPROP 1 LASTPIN (2900 3975) $PN 1
J 0
(2912 3987);
DISPLAY 0.787234 (2912 3987);
FORCEPROP 1 LASTPIN (3100 3975) $PN 2
J 0
(3062 3987);
DISPLAY 0.787234 (3062 3987);
FORCEPROP 2 LAST CDS_LIB pure_quanta
J 0
(3000 3975);
PAINT MONO (3000 3975);
DISPLAY INVISIBLE (3000 3975);
FORCEPROP 1 LAST PATH I82
J 0
(2950 4125);
DISPLAY 0.978723 (2950 4125);
PAINT WHITE (2950 4125);
DISPLAY INVISIBLE (2950 4125);
FORCEPROP 2 LAST CDS_LOCATION R1752
J 0
(2950 4175);
DISPLAY 1.021277 (2950 4175);
DISPLAY INVISIBLE (2950 4175);
FORCEPROP 2 LAST $SEC 1
J 0
(2950 4175);
DISPLAY 0.680851 (2950 4175);
PAINT MONO (2950 4175);
DISPLAY INVISIBLE (2950 4175);
FORCEPROP 2 LAST CDS_SEC 1
J 0
(2950 4175);
DISPLAY 1.021277 (2950 4175);
DISPLAY INVISIBLE (2950 4175);
FORCEADD OFFPAGE..1
(1625 3500);
FORCEPROP 2 LAST $XR0 240 
J 0
(1343 3500);
DISPLAY 0.638298 (1343 3500);
PAINT MONO (1343 3500);
FORCEPROP 2 LAST CDS_LIB standard
J 0
(1625 3500);
PAINT MONO (1625 3500);
DISPLAY INVISIBLE (1625 3500);
FORCEPROP 1 LAST OFFPAGE TRUE
J 0
(1950 3375);
DISPLAY 0.872340 (1950 3375);
PAINT GREEN (1950 3375);
DISPLAY INVISIBLE (1950 3375);
FORCEPROP 1 LAST COMMENT_BODY TRUE
J 0
(1750 3400);
DISPLAY 0.872340 (1750 3400);
PAINT GREEN (1750 3400);
DISPLAY INVISIBLE (1750 3400);
FORCEPROP 2 LAST PATH I83
J 0
(1375 3550);
DISPLAY 1.021277 (1375 3550);
DISPLAY INVISIBLE (1375 3550);
FORCEADD Q_RES..1
(3000 3725);
FORCEPROP 1 LAST PART_NUMBER CS03322FB03
J 0
(2900 3800);
DISPLAY 0.404255 (2900 3800);
DISPLAY INVISIBLE (2900 3800);
FORCEPROP 1 LAST MATERIAL CHIP
J 0
(3250 3725);
DISPLAY 0.404255 (3250 3725);
FORCEPROP 1 LAST TOLERANCE 1%
J 0
(3200 3725);
DISPLAY 0.404255 (3200 3725);
FORCEPROP 1 LAST VALUE 33.2
J 2
(3175 3725);
DISPLAY 0.404255 (3175 3725);
FORCEPROP 1 LAST WATTAGE 1/16W
J 2
(3125 3825);
DISPLAY 0.404255 (3125 3825);
FORCEPROP 1 LAST PACK_TYPE 0402LF
J 0
(2900 3825);
DISPLAY 0.404255 (2900 3825);
FORCEPROP 1 LAST $LOCATION R1753
J 0
(2750 3725);
DISPLAY 0.638298 (2750 3725);
FORCEPROP 1 LASTPIN (2900 3725) $PN 1
J 0
(2912 3737);
DISPLAY 0.787234 (2912 3737);
FORCEPROP 1 LASTPIN (3100 3725) $PN 2
J 0
(3062 3737);
DISPLAY 0.787234 (3062 3737);
FORCEPROP 2 LAST CDS_LIB pure_quanta
J 0
(3000 3725);
PAINT MONO (3000 3725);
DISPLAY INVISIBLE (3000 3725);
FORCEPROP 1 LAST PATH I84
J 0
(2950 3875);
DISPLAY 0.978723 (2950 3875);
PAINT WHITE (2950 3875);
DISPLAY INVISIBLE (2950 3875);
FORCEPROP 2 LAST CDS_LOCATION R1753
J 0
(2950 3925);
DISPLAY 1.021277 (2950 3925);
DISPLAY INVISIBLE (2950 3925);
FORCEPROP 2 LAST $SEC 1
J 0
(2950 3925);
DISPLAY 0.680851 (2950 3925);
PAINT MONO (2950 3925);
DISPLAY INVISIBLE (2950 3925);
FORCEPROP 2 LAST CDS_SEC 1
J 0
(2950 3925);
DISPLAY 1.021277 (2950 3925);
DISPLAY INVISIBLE (2950 3925);
FORCEADD OFFPAGE..2
(4500 3500);
FORCEPROP 2 LAST $XR0 213 
J 0
(4689 3500);
DISPLAY 0.638298 (4689 3500);
PAINT MONO (4689 3500);
FORCEPROP 1 LAST COMMENT_BODY TRUE
J 0
(4455 3405);
DISPLAY 1.170213 (4455 3405);
PAINT GREEN (4455 3405);
DISPLAY INVISIBLE (4455 3405);
FORCEPROP 1 LAST OFFPAGE TRUE
J 0
(4825 3375);
DISPLAY 1.170213 (4825 3375);
PAINT GREEN (4825 3375);
DISPLAY INVISIBLE (4825 3375);
FORCEPROP 2 LAST CDS_LIB standard
J 0
(4500 3500);
PAINT MONO (4500 3500);
DISPLAY INVISIBLE (4500 3500);
FORCEPROP 2 LAST PATH I85
J 0
(4700 3550);
DISPLAY 1.021277 (4700 3550);
DISPLAY INVISIBLE (4700 3550);
FORCEADD OFFPAGE..2
(4500 3725);
FORCEPROP 2 LAST $XR0 213 
J 0
(4689 3725);
DISPLAY 0.638298 (4689 3725);
PAINT MONO (4689 3725);
FORCEPROP 1 LAST COMMENT_BODY TRUE
J 0
(4455 3630);
DISPLAY 1.170213 (4455 3630);
PAINT GREEN (4455 3630);
DISPLAY INVISIBLE (4455 3630);
FORCEPROP 1 LAST OFFPAGE TRUE
J 0
(4825 3600);
DISPLAY 1.170213 (4825 3600);
PAINT GREEN (4825 3600);
DISPLAY INVISIBLE (4825 3600);
FORCEPROP 2 LAST CDS_LIB standard
J 0
(4500 3725);
PAINT MONO (4500 3725);
DISPLAY INVISIBLE (4500 3725);
FORCEPROP 2 LAST PATH I86
J 0
(4700 3775);
DISPLAY 1.021277 (4700 3775);
DISPLAY INVISIBLE (4700 3775);
FORCEADD OFFPAGE..1
(1625 3725);
FORCEPROP 2 LAST $XR0 240 
J 0
(1343 3725);
DISPLAY 0.638298 (1343 3725);
PAINT MONO (1343 3725);
FORCEPROP 2 LAST CDS_LIB standard
J 0
(1625 3725);
PAINT MONO (1625 3725);
DISPLAY INVISIBLE (1625 3725);
FORCEPROP 1 LAST OFFPAGE TRUE
J 0
(1950 3600);
DISPLAY 0.872340 (1950 3600);
PAINT GREEN (1950 3600);
DISPLAY INVISIBLE (1950 3600);
FORCEPROP 1 LAST COMMENT_BODY TRUE
J 0
(1750 3625);
DISPLAY 0.872340 (1750 3625);
PAINT GREEN (1750 3625);
DISPLAY INVISIBLE (1750 3625);
FORCEPROP 2 LAST PATH I87
J 0
(1375 3775);
DISPLAY 1.021277 (1375 3775);
DISPLAY INVISIBLE (1375 3775);
FORCEADD Q_RES..1
(3000 3500);
FORCEPROP 1 LAST PART_NUMBER CS03322FB03
J 0
(2900 3575);
DISPLAY 0.404255 (2900 3575);
DISPLAY INVISIBLE (2900 3575);
FORCEPROP 1 LAST MATERIAL CHIP
J 0
(3250 3500);
DISPLAY 0.404255 (3250 3500);
FORCEPROP 1 LAST VALUE 33.2
J 2
(3175 3500);
DISPLAY 0.404255 (3175 3500);
FORCEPROP 1 LAST TOLERANCE 1%
J 0
(3200 3500);
DISPLAY 0.404255 (3200 3500);
FORCEPROP 1 LAST WATTAGE 1/16W
J 2
(3125 3600);
DISPLAY 0.404255 (3125 3600);
FORCEPROP 1 LAST PACK_TYPE 0402LF
J 0
(2900 3600);
DISPLAY 0.404255 (2900 3600);
FORCEPROP 1 LAST $LOCATION R1754
J 0
(2750 3500);
DISPLAY 0.638298 (2750 3500);
FORCEPROP 1 LASTPIN (2900 3500) $PN 1
J 0
(2912 3512);
DISPLAY 0.787234 (2912 3512);
FORCEPROP 1 LASTPIN (3100 3500) $PN 2
J 0
(3062 3512);
DISPLAY 0.787234 (3062 3512);
FORCEPROP 2 LAST CDS_LIB pure_quanta
J 0
(3000 3500);
PAINT MONO (3000 3500);
DISPLAY INVISIBLE (3000 3500);
FORCEPROP 1 LAST PATH I88
J 0
(2950 3650);
DISPLAY 0.978723 (2950 3650);
PAINT WHITE (2950 3650);
DISPLAY INVISIBLE (2950 3650);
FORCEPROP 2 LAST CDS_LOCATION R1754
J 0
(2950 3700);
DISPLAY 1.021277 (2950 3700);
DISPLAY INVISIBLE (2950 3700);
FORCEPROP 2 LAST $SEC 1
J 0
(2950 3700);
DISPLAY 0.680851 (2950 3700);
PAINT MONO (2950 3700);
DISPLAY INVISIBLE (2950 3700);
FORCEPROP 2 LAST CDS_SEC 1
J 0
(2950 3700);
DISPLAY 1.021277 (2950 3700);
DISPLAY INVISIBLE (2950 3700);
FORCEADD OFFPAGE..5
(1625 4200);
FORCEPROP 2 LAST $XR0 240 
J 0
(1370 4200);
DISPLAY 0.638298 (1370 4200);
PAINT MONO (1370 4200);
FORCEPROP 2 LAST CDS_LIB standard
J 0
(1625 4200);
PAINT MONO (1625 4200);
DISPLAY INVISIBLE (1625 4200);
FORCEPROP 1 LAST COMMENT_BODY TRUE
J 0
(1725 4125);
DISPLAY 0.872340 (1725 4125);
PAINT PEACH (1725 4125);
DISPLAY INVISIBLE (1725 4125);
FORCEPROP 1 LAST OFFPAGE TRUE
J 0
(1950 4075);
DISPLAY 0.872340 (1950 4075);
PAINT GREEN (1950 4075);
DISPLAY INVISIBLE (1950 4075);
FORCEPROP 2 LAST PATH I89
J 0
(1350 4250);
DISPLAY 1.021277 (1350 4250);
DISPLAY INVISIBLE (1350 4250);
FORCEADD Q_RES..1
(-1625 4200);
FORCEPROP 1 LAST PART_NUMBER CS03322FB03
J 0
(-1750 4250);
DISPLAY 0.404255 (-1750 4250);
DISPLAY INVISIBLE (-1750 4250);
FORCEPROP 1 LAST TOLERANCE 1%
J 0
(-1450 4200);
DISPLAY 0.510638 (-1450 4200);
FORCEPROP 1 LAST VALUE 33.2
J 2
(-1475 4200);
DISPLAY 0.510638 (-1475 4200);
FORCEPROP 1 LAST PACK_TYPE 0402LF
J 0
(-1375 4200);
DISPLAY 0.510638 (-1375 4200);
FORCEPROP 1 LAST MATERIAL CHIP
J 0
(-1750 4275);
DISPLAY 0.404255 (-1750 4275);
FORCEPROP 1 LAST WATTAGE 1/16W
J 2
(-1525 4275);
DISPLAY 0.404255 (-1525 4275);
FORCEPROP 1 LAST $LOCATION R981
J 0
(-1850 4200);
DISPLAY 0.638298 (-1850 4200);
FORCEPROP 1 LASTPIN (-1725 4200) $PN 1
J 0
(-1713 4212);
DISPLAY 0.787234 (-1713 4212);
FORCEPROP 1 LASTPIN (-1525 4200) $PN 2
J 0
(-1563 4212);
DISPLAY 0.787234 (-1563 4212);
FORCEPROP 1 LAST PATH I9
J 0
(-1675 4350);
DISPLAY 0.978723 (-1675 4350);
PAINT WHITE (-1675 4350);
DISPLAY INVISIBLE (-1675 4350);
FORCEPROP 2 LAST CDS_LIB pure_quanta
J 0
(-1625 4200);
PAINT MONO (-1625 4200);
DISPLAY INVISIBLE (-1625 4200);
FORCEPROP 2 LAST CDS_LOCATION R981
J 0
(-1675 4400);
DISPLAY 1.021277 (-1675 4400);
DISPLAY INVISIBLE (-1675 4400);
FORCEPROP 2 LAST $SEC 1
J 0
(-1675 4400);
DISPLAY 0.680851 (-1675 4400);
PAINT MONO (-1675 4400);
DISPLAY INVISIBLE (-1675 4400);
FORCEPROP 2 LAST CDS_SEC 1
J 0
(-1675 4400);
DISPLAY 1.021277 (-1675 4400);
DISPLAY INVISIBLE (-1675 4400);
FORCEADD OFFPAGE..4
(4500 4200);
FORCEPROP 2 LAST $XR0 213 
J 0
(4686 4200);
DISPLAY 0.638298 (4686 4200);
PAINT MONO (4686 4200);
FORCEPROP 1 LAST COMMENT_BODY TRUE
J 0
(4475 4100);
DISPLAY 0.872340 (4475 4100);
PAINT PEACH (4475 4100);
DISPLAY INVISIBLE (4475 4100);
FORCEPROP 1 LAST OFFPAGE TRUE
J 0
(4825 4075);
DISPLAY 0.872340 (4825 4075);
PAINT GREEN (4825 4075);
DISPLAY INVISIBLE (4825 4075);
FORCEPROP 2 LAST CDS_LIB standard
J 0
(4500 4200);
PAINT MONO (4500 4200);
DISPLAY INVISIBLE (4500 4200);
FORCEPROP 2 LAST PATH I90
J 0
(4850 4250);
DISPLAY 1.021277 (4850 4250);
DISPLAY INVISIBLE (4850 4250);
FORCEADD Q_RES..1
(3025 2375);
FORCEPROP 1 LAST PART_NUMBER CS03322FB03
J 0
(2925 2450);
DISPLAY 0.404255 (2925 2450);
DISPLAY INVISIBLE (2925 2450);
FORCEPROP 1 LAST WATTAGE 1/16W
J 2
(3150 2475);
DISPLAY 0.404255 (3150 2475);
FORCEPROP 1 LAST TOLERANCE 1%
J 0
(3225 2375);
DISPLAY 0.404255 (3225 2375);
FORCEPROP 1 LAST VALUE 33.2
J 2
(3200 2375);
DISPLAY 0.404255 (3200 2375);
FORCEPROP 1 LAST PACK_TYPE 0402LF
J 0
(2925 2475);
DISPLAY 0.404255 (2925 2475);
FORCEPROP 1 LAST MATERIAL CHIP
J 0
(3275 2375);
DISPLAY 0.404255 (3275 2375);
FORCEPROP 1 LAST $LOCATION R1758
J 0
(2775 2375);
DISPLAY 0.638298 (2775 2375);
FORCEPROP 1 LASTPIN (2925 2375) $PN 1
J 0
(2937 2387);
DISPLAY 0.787234 (2937 2387);
FORCEPROP 1 LASTPIN (3125 2375) $PN 2
J 0
(3087 2387);
DISPLAY 0.787234 (3087 2387);
FORCEPROP 2 LAST CDS_LIB pure_quanta
J 0
(3025 2375);
PAINT MONO (3025 2375);
DISPLAY INVISIBLE (3025 2375);
FORCEPROP 1 LAST PATH I91
J 0
(2975 2525);
DISPLAY 0.978723 (2975 2525);
PAINT WHITE (2975 2525);
DISPLAY INVISIBLE (2975 2525);
FORCEPROP 2 LAST CDS_LOCATION R1758
J 0
(2975 2575);
DISPLAY 1.021277 (2975 2575);
DISPLAY INVISIBLE (2975 2575);
FORCEPROP 2 LAST $SEC 1
J 0
(2975 2575);
DISPLAY 0.680851 (2975 2575);
PAINT MONO (2975 2575);
DISPLAY INVISIBLE (2975 2575);
FORCEPROP 2 LAST CDS_SEC 1
J 0
(2975 2575);
DISPLAY 1.021277 (2975 2575);
DISPLAY INVISIBLE (2975 2575);
FORCEADD OFFPAGE..4
(4500 3075);
FORCEPROP 2 LAST $XR0 213 
J 0
(4686 3075);
DISPLAY 0.638298 (4686 3075);
PAINT MONO (4686 3075);
FORCEPROP 1 LAST COMMENT_BODY TRUE
J 0
(4475 2975);
DISPLAY 0.872340 (4475 2975);
PAINT PEACH (4475 2975);
DISPLAY INVISIBLE (4475 2975);
FORCEPROP 1 LAST OFFPAGE TRUE
J 0
(4825 2950);
DISPLAY 0.872340 (4825 2950);
PAINT GREEN (4825 2950);
DISPLAY INVISIBLE (4825 2950);
FORCEPROP 2 LAST PATH I92
J 0
(4850 3125);
DISPLAY 1.021277 (4850 3125);
DISPLAY INVISIBLE (4850 3125);
FORCEPROP 2 LAST CDS_LIB standard
J 0
(4500 3075);
PAINT MONO (4500 3075);
DISPLAY INVISIBLE (4500 3075);
FORCEADD OFFPAGE..2
(4500 2850);
FORCEPROP 2 LAST $XR0 213 
J 0
(4689 2850);
DISPLAY 0.638298 (4689 2850);
PAINT MONO (4689 2850);
FORCEPROP 2 LAST PATH I93
J 0
(4700 2900);
DISPLAY 1.021277 (4700 2900);
DISPLAY INVISIBLE (4700 2900);
FORCEPROP 1 LAST COMMENT_BODY TRUE
J 0
(4455 2755);
DISPLAY 1.170213 (4455 2755);
PAINT GREEN (4455 2755);
DISPLAY INVISIBLE (4455 2755);
FORCEPROP 1 LAST OFFPAGE TRUE
J 0
(4825 2725);
DISPLAY 1.170213 (4825 2725);
PAINT GREEN (4825 2725);
DISPLAY INVISIBLE (4825 2725);
FORCEPROP 2 LAST CDS_LIB standard
J 0
(4500 2850);
PAINT MONO (4500 2850);
DISPLAY INVISIBLE (4500 2850);
FORCEADD OFFPAGE..2
(4500 2600);
FORCEPROP 2 LAST $XR0 213 
J 0
(4689 2600);
DISPLAY 0.638298 (4689 2600);
PAINT MONO (4689 2600);
FORCEPROP 1 LAST COMMENT_BODY TRUE
J 0
(4455 2505);
DISPLAY 1.170213 (4455 2505);
PAINT GREEN (4455 2505);
DISPLAY INVISIBLE (4455 2505);
FORCEPROP 1 LAST OFFPAGE TRUE
J 0
(4825 2475);
DISPLAY 1.170213 (4825 2475);
PAINT GREEN (4825 2475);
DISPLAY INVISIBLE (4825 2475);
FORCEPROP 2 LAST CDS_LIB standard
J 0
(4500 2600);
PAINT MONO (4500 2600);
DISPLAY INVISIBLE (4500 2600);
FORCEPROP 2 LAST PATH I94
J 0
(4700 2650);
DISPLAY 1.021277 (4700 2650);
DISPLAY INVISIBLE (4700 2650);
FORCEADD OFFPAGE..2
(4500 2375);
FORCEPROP 2 LAST $XR0 213 
J 0
(4689 2375);
DISPLAY 0.638298 (4689 2375);
PAINT MONO (4689 2375);
FORCEPROP 2 LAST CDS_LIB standard
J 0
(4500 2375);
PAINT MONO (4500 2375);
DISPLAY INVISIBLE (4500 2375);
FORCEPROP 1 LAST OFFPAGE TRUE
J 0
(4825 2250);
DISPLAY 1.170213 (4825 2250);
PAINT GREEN (4825 2250);
DISPLAY INVISIBLE (4825 2250);
FORCEPROP 1 LAST COMMENT_BODY TRUE
J 0
(4455 2280);
DISPLAY 1.170213 (4455 2280);
PAINT GREEN (4455 2280);
DISPLAY INVISIBLE (4455 2280);
FORCEPROP 2 LAST PATH I95
J 0
(4700 2425);
DISPLAY 1.021277 (4700 2425);
DISPLAY INVISIBLE (4700 2425);
FORCEADD Q_RES..1
(3025 3075);
FORCEPROP 1 LAST PART_NUMBER CS03322FB03
J 0
(2925 3150);
DISPLAY 0.404255 (2925 3150);
DISPLAY INVISIBLE (2925 3150);
FORCEPROP 1 LAST TOLERANCE 1%
J 0
(3225 3075);
DISPLAY 0.404255 (3225 3075);
FORCEPROP 1 LAST MATERIAL CHIP
J 0
(3275 3075);
DISPLAY 0.404255 (3275 3075);
FORCEPROP 1 LAST PACK_TYPE 0402LF
J 0
(2925 3175);
DISPLAY 0.404255 (2925 3175);
FORCEPROP 1 LAST WATTAGE 1/16W
J 2
(3150 3175);
DISPLAY 0.404255 (3150 3175);
FORCEPROP 1 LAST VALUE 33.2
J 2
(3200 3075);
DISPLAY 0.404255 (3200 3075);
FORCEPROP 1 LAST $LOCATION R1755
J 0
(2775 3075);
DISPLAY 0.638298 (2775 3075);
FORCEPROP 1 LASTPIN (2925 3075) $PN 1
J 0
(2937 3087);
DISPLAY 0.787234 (2937 3087);
FORCEPROP 1 LASTPIN (3125 3075) $PN 2
J 0
(3087 3087);
DISPLAY 0.787234 (3087 3087);
FORCEPROP 2 LAST CDS_LIB pure_quanta
J 0
(3025 3075);
PAINT MONO (3025 3075);
DISPLAY INVISIBLE (3025 3075);
FORCEPROP 1 LAST PATH I96
J 0
(2975 3225);
DISPLAY 0.978723 (2975 3225);
PAINT WHITE (2975 3225);
DISPLAY INVISIBLE (2975 3225);
FORCEPROP 2 LAST CDS_LOCATION R1755
J 0
(2975 3275);
DISPLAY 1.021277 (2975 3275);
DISPLAY INVISIBLE (2975 3275);
FORCEPROP 2 LAST $SEC 1
J 0
(2975 3275);
DISPLAY 0.680851 (2975 3275);
PAINT MONO (2975 3275);
DISPLAY INVISIBLE (2975 3275);
FORCEPROP 2 LAST CDS_SEC 1
J 0
(2975 3275);
DISPLAY 1.021277 (2975 3275);
DISPLAY INVISIBLE (2975 3275);
FORCEADD OFFPAGE..5
(1625 3075);
FORCEPROP 2 LAST $XR0 240 
J 0
(1370 3075);
DISPLAY 0.638298 (1370 3075);
PAINT MONO (1370 3075);
FORCEPROP 1 LAST COMMENT_BODY TRUE
J 0
(1725 3000);
DISPLAY 0.872340 (1725 3000);
PAINT PEACH (1725 3000);
DISPLAY INVISIBLE (1725 3000);
FORCEPROP 1 LAST OFFPAGE TRUE
J 0
(1950 2950);
DISPLAY 0.872340 (1950 2950);
PAINT GREEN (1950 2950);
DISPLAY INVISIBLE (1950 2950);
FORCEPROP 2 LAST PATH I97
J 0
(1350 3125);
DISPLAY 1.021277 (1350 3125);
DISPLAY INVISIBLE (1350 3125);
FORCEPROP 2 LAST CDS_LIB standard
J 0
(1625 3075);
PAINT MONO (1625 3075);
DISPLAY INVISIBLE (1625 3075);
FORCEADD Q_RES..1
(3025 2850);
FORCEPROP 1 LAST PART_NUMBER CS03322FB03
J 0
(2925 2925);
DISPLAY 0.404255 (2925 2925);
DISPLAY INVISIBLE (2925 2925);
FORCEPROP 1 LAST WATTAGE 1/16W
J 2
(3150 2950);
DISPLAY 0.404255 (3150 2950);
FORCEPROP 1 LAST MATERIAL CHIP
J 0
(3275 2850);
DISPLAY 0.404255 (3275 2850);
FORCEPROP 1 LAST PACK_TYPE 0402LF
J 0
(2925 2950);
DISPLAY 0.404255 (2925 2950);
FORCEPROP 1 LAST VALUE 33.2
J 2
(3200 2850);
DISPLAY 0.404255 (3200 2850);
FORCEPROP 1 LAST TOLERANCE 1%
J 0
(3225 2850);
DISPLAY 0.404255 (3225 2850);
FORCEPROP 1 LAST $LOCATION R1756
J 0
(2775 2850);
DISPLAY 0.638298 (2775 2850);
FORCEPROP 1 LASTPIN (2925 2850) $PN 1
J 0
(2937 2862);
DISPLAY 0.787234 (2937 2862);
FORCEPROP 1 LASTPIN (3125 2850) $PN 2
J 0
(3087 2862);
DISPLAY 0.787234 (3087 2862);
FORCEPROP 2 LAST CDS_LIB pure_quanta
J 0
(3025 2850);
PAINT MONO (3025 2850);
DISPLAY INVISIBLE (3025 2850);
FORCEPROP 1 LAST PATH I98
J 0
(2975 3000);
DISPLAY 0.978723 (2975 3000);
PAINT WHITE (2975 3000);
DISPLAY INVISIBLE (2975 3000);
FORCEPROP 2 LAST CDS_LOCATION R1756
J 0
(2975 3050);
DISPLAY 1.021277 (2975 3050);
DISPLAY INVISIBLE (2975 3050);
FORCEPROP 2 LAST $SEC 1
J 0
(2975 3050);
DISPLAY 0.680851 (2975 3050);
PAINT MONO (2975 3050);
DISPLAY INVISIBLE (2975 3050);
FORCEPROP 2 LAST CDS_SEC 1
J 0
(2975 3050);
DISPLAY 1.021277 (2975 3050);
DISPLAY INVISIBLE (2975 3050);
FORCEADD Q_RES..1
(3025 2600);
FORCEPROP 1 LAST PART_NUMBER CS03322FB03
J 0
(2925 2675);
DISPLAY 0.404255 (2925 2675);
DISPLAY INVISIBLE (2925 2675);
FORCEPROP 1 LAST MATERIAL CHIP
J 0
(3275 2600);
DISPLAY 0.404255 (3275 2600);
FORCEPROP 1 LAST PACK_TYPE 0402LF
J 0
(2925 2700);
DISPLAY 0.404255 (2925 2700);
FORCEPROP 1 LAST WATTAGE 1/16W
J 2
(3150 2700);
DISPLAY 0.404255 (3150 2700);
FORCEPROP 1 LAST VALUE 33.2
J 2
(3200 2600);
DISPLAY 0.404255 (3200 2600);
FORCEPROP 1 LAST TOLERANCE 1%
J 0
(3225 2600);
DISPLAY 0.404255 (3225 2600);
FORCEPROP 1 LAST $LOCATION R1757
J 0
(2775 2600);
DISPLAY 0.638298 (2775 2600);
FORCEPROP 1 LASTPIN (2925 2600) $PN 1
J 0
(2937 2612);
DISPLAY 0.787234 (2937 2612);
FORCEPROP 1 LASTPIN (3125 2600) $PN 2
J 0
(3087 2612);
DISPLAY 0.787234 (3087 2612);
FORCEPROP 2 LAST CDS_LIB pure_quanta
J 0
(3025 2600);
PAINT MONO (3025 2600);
DISPLAY INVISIBLE (3025 2600);
FORCEPROP 1 LAST PATH I99
J 0
(2975 2750);
DISPLAY 0.978723 (2975 2750);
PAINT WHITE (2975 2750);
DISPLAY INVISIBLE (2975 2750);
FORCEPROP 2 LAST CDS_LOCATION R1757
J 0
(2975 2800);
DISPLAY 1.021277 (2975 2800);
DISPLAY INVISIBLE (2975 2800);
FORCEPROP 2 LAST $SEC 1
J 0
(2975 2800);
DISPLAY 0.680851 (2975 2800);
PAINT MONO (2975 2800);
DISPLAY INVISIBLE (2975 2800);
FORCEPROP 2 LAST CDS_SEC 1
J 0
(2975 2800);
DISPLAY 1.021277 (2975 2800);
DISPLAY INVISIBLE (2975 2800);
FORCEADD QUANTA_TITLE_BLOCK_C..1
(5275 -1725);
FORCEPROP 0 LAST CDS_CON_LAST_MODIFIED Fri Aug 25 14:03:43 2023
J 0
(3390 -1710);
PAINT MONO (3390 -1710);
DISPLAY INVISIBLE (3390 -1710);
FORCEPROP 2 LAST CUSTOM_TXT_CDS <XR_PAGE_TITLE>
J 0
(-2615 3525);
DISPLAY 0.638298 (-2615 3525);
PAINT PINK (-2615 3525);
DISPLAY INVISIBLE (-2615 3525);
FORCEPROP 2 LAST CUSTOM_TXT_CDS <CON_LAST_MODIFIED>
J 0
(3390 -1710);
DISPLAY 0.978723 (3390 -1710);
FORCEPROP 2 LAST CUSTOM_TXT_CDS <NAME_2>
J 0
(2100 -1675);
FORCEPROP 2 LAST CUSTOM_TXT_CDS <NAME_1>
J 0
(2100 -1550);
FORCEPROP 2 LAST CUSTOM_TXT_CDS <Q_NUMBER>
J 0
(3872 -1622);
DISPLAY 1.212766 (3872 -1622);
FORCEPROP 2 LAST CUSTOM_TXT_CDS <Q_PROJ>
J 0
(2893 -1623);
DISPLAY 1.212766 (2893 -1623);
FORCEPROP 2 LAST CUSTOM_TXT_CDS <Q_REV>
J 0
(5091 -1622);
DISPLAY 1.212766 (5091 -1622);
FORCEPROP 2 LAST CUSTOM_TXT_CDS <CON_PAGE_NUM> OF <CON_TOTAL_PAGES>
J 0
(4829 -1707);
DISPLAY 0.978723 (4829 -1707);
FORCEPROP 1 LAST Q_TITLE MAIN FPGA / PFR - SI (1/2)
J 0
(-4016 -1699);
DISPLAY 2.446809 (-4016 -1699);
PAINT GREEN (-4016 -1699);
FORCEPROP 1 LAST Q_DEPT 
J 1
(1512 -1676);
DISPLAY 1.957447 (1512 -1676);
PAINT GREEN (1512 -1676);
FORCEPROP 2 LAST CDS_XR_PAGE_TITLE CR-222 : @S9S_MB_2U_LIB.S9S_MB_2U(SCH_1):PAGE222
J 0
(-2615 3525);
DISPLAY 0.638298 (-2615 3525);
PAINT PINK (-2615 3525);
DISPLAY INVISIBLE (-2615 3525);
FORCEPROP 2 LAST CDS_LIB pure_quanta
J 0
(5275 -1725);
PAINT MONO (5275 -1725);
DISPLAY INVISIBLE (5275 -1725);
FORCEPROP 1 LAST CDS_LMAN_SYM_OUTLINE -9475,6775,100,-125
J 0
(5275 -1725);
DISPLAY 0.468085 (5275 -1725);
PAINT GREEN (5275 -1725);
DISPLAY INVISIBLE (5275 -1725);
FORCEPROP 2 LAST PAGE_BORDER TRUE
J 0
(-2615 3525);
DISPLAY 0.638298 (-2615 3525);
PAINT PINK (-2615 3525);
DISPLAY INVISIBLE (-2615 3525);
FORCEPROP 1 LAST COMMENT_BODY TRUE
J 0
(5287 -1738);
DISPLAY 0.978723 (5287 -1738);
PAINT GREEN (5287 -1738);
DISPLAY INVISIBLE (5287 -1738);
WIRE 16 -1 (-3275 -375)(-1725 -375);
FORCEPROP 2 LAST SIG_NAME FM_CPU0_SKTOCC_LVT3_N
J 0
(-3160 -365);
DISPLAY 0.851064 (-3160 -365);
PAINT WHITE (-3160 -365);
WIRE 16 -1 (-3275 -600)(-1725 -600);
FORCEPROP 2 LAST SIG_NAME FM_CPU1_SKTOCC_LVT3_N
J 0
(-3160 -590);
DISPLAY 0.851064 (-3160 -590);
PAINT WHITE (-3160 -590);
WIRE 16 2175 (-2150 300)(600 300);
WIRE 16 2175 (600 300)(600 75);
WIRE 16 2175 (-2150 300)(-2150 75);
WIRE 16 2175 (-2150 75)(600 75);
WIRE 16 -1 (-2450 150)(-1750 150);
WIRE 16 -1 (-2450 350)(-2450 150);
WIRE 16 -1 (-2450 350)(-1725 350);
WIRE 16 -1 (-3275 350)(-2450 350);
FORCEPROP 2 LAST SIG_NAME PWRGD_P3V3_AUX
J 0
(-3160 360);
DISPLAY 0.851064 (-3160 360);
PAINT WHITE (-3160 360);
WIRE 16 -1 (3100 3725)(4450 3725);
FORCEPROP 2 LAST SIG_NAME SGPIO_DEBUG_PLD_DIN
J 0
(3565 3735);
DISPLAY 0.851064 (3565 3735);
PAINT WHITE (3565 3735);
WIRE 16 -1 (3125 2850)(4450 2850);
FORCEPROP 2 LAST SIG_NAME SGPIO_BMC_CLK
J 0
(3540 2860);
DISPLAY 0.851064 (3540 2860);
PAINT WHITE (3540 2860);
WIRE 16 -1 (3125 2600)(4450 2600);
FORCEPROP 2 LAST SIG_NAME SGPIO_BMC_DIN_R
J 0
(3540 2610);
DISPLAY 0.851064 (3540 2610);
PAINT WHITE (3540 2610);
WIRE 16 -1 (3125 3075)(4450 3075);
FORCEPROP 2 LAST SIG_NAME SGPIO_BMC_DOUT
J 0
(3540 3085);
DISPLAY 0.851064 (3540 3085);
PAINT WHITE (3540 3085);
WIRE 16 -1 (3100 3500)(4450 3500);
FORCEPROP 2 LAST SIG_NAME SGPIO_DEBUG_PLD_LD_N
J 0
(3540 3510);
DISPLAY 0.851064 (3540 3510);
PAINT WHITE (3540 3510);
WIRE 16 -1 (1675 2375)(2925 2375);
FORCEPROP 2 LAST SIG_NAME SGPIO_LD_1
J 0
(1790 2385);
DISPLAY 0.851064 (1790 2385);
PAINT WHITE (1790 2385);
WIRE 16 -1 (1675 2600)(2925 2600);
FORCEPROP 2 LAST SIG_NAME SGPIO_DI_1
J 0
(1790 2610);
DISPLAY 0.851064 (1790 2610);
PAINT WHITE (1790 2610);
WIRE 16 -1 (1675 2850)(2925 2850);
FORCEPROP 2 LAST SIG_NAME SGPIO_CLK_1
J 0
(1790 2860);
DISPLAY 0.851064 (1790 2860);
PAINT WHITE (1790 2860);
WIRE 16 -1 (1675 3075)(2925 3075);
FORCEPROP 2 LAST SIG_NAME SGPIO_DO_1
J 0
(1790 3085);
DISPLAY 0.851064 (1790 3085);
PAINT WHITE (1790 3085);
WIRE 16 -1 (3125 2150)(4450 2150);
FORCEPROP 2 LAST SIG_NAME RST_SGPIO_RESET_N_R
J 0
(3540 2160);
DISPLAY 0.851064 (3540 2160);
PAINT WHITE (3540 2160);
WIRE 16 -1 (3125 2375)(4450 2375);
FORCEPROP 2 LAST SIG_NAME SGPIO_BMC_LD_N
J 0
(3540 2385);
DISPLAY 0.851064 (3540 2385);
PAINT WHITE (3540 2385);
WIRE 16 -1 (3125 1925)(4450 1925);
FORCEPROP 2 LAST SIG_NAME IRQ_SGPIO_INTR_N_R
J 0
(3540 1935);
DISPLAY 0.851064 (3540 1935);
PAINT WHITE (3540 1935);
WIRE 16 -1 (3100 3975)(4450 3975);
FORCEPROP 2 LAST SIG_NAME SGPIO_DEBUG_PLD_CLK
J 0
(3565 3985);
DISPLAY 0.851064 (3565 3985);
PAINT WHITE (3565 3985);
WIRE 16 -1 (3100 4200)(4450 4200);
FORCEPROP 2 LAST SIG_NAME SGPIO_DEBUG_PLD_DOUT
J 0
(3565 4210);
DISPLAY 0.851064 (3565 4210);
PAINT WHITE (3565 4210);
WIRE 16 -1 (1675 1925)(2925 1925);
FORCEPROP 2 LAST SIG_NAME IRQ_SGPIO_INTR_N
J 0
(1790 1935);
DISPLAY 0.851064 (1790 1935);
PAINT WHITE (1790 1935);
WIRE 16 -1 (1675 2150)(2925 2150);
FORCEPROP 2 LAST SIG_NAME RST_SGPIO_RESET_N
J 0
(1790 2160);
DISPLAY 0.851064 (1790 2160);
PAINT WHITE (1790 2160);
WIRE 16 -1 (-3275 2375)(-1725 2375);
FORCEPROP 2 LAST SIG_NAME FM_PVCCFA_EHV_FIVRA_CPU1_R_EN
J 0
(-3160 2385);
DISPLAY 0.851064 (-3160 2385);
PAINT WHITE (-3160 2385);
WIRE 16 -1 (-1550 150)(250 150);
FORCEPROP 2 LAST SIG_NAME PWRGD_P3V3_AUX_PDB
J 0
(-935 160);
DISPLAY 0.851064 (-935 160);
PAINT WHITE (-935 160);
WIRE 16 -1 (-1525 350)(275 350);
FORCEPROP 2 LAST SIG_NAME PWRGD_P3V3_AUX_PLD
J 0
(-935 360);
DISPLAY 0.851064 (-935 360);
PAINT WHITE (-935 360);
WIRE 16 -1 (-1525 1250)(300 1250);
FORCEPROP 2 LAST SIG_NAME PWRGD_CPUPWRGD_LVC1_R
J 0
(-935 1260);
DISPLAY 0.851064 (-935 1260);
PAINT WHITE (-935 1260);
WIRE 16 -1 (-1525 1725)(275 1725);
FORCEPROP 2 LAST SIG_NAME PWRGD_SYS_PWROK
J 0
(-935 1735);
DISPLAY 0.851064 (-935 1735);
PAINT WHITE (-935 1735);
WIRE 16 -1 (-3275 2850)(-1725 2850);
FORCEPROP 2 LAST SIG_NAME FM_PVCCFA_EHV_CPU1_R_EN
J 0
(-3160 2860);
DISPLAY 0.851064 (-3160 2860);
PAINT WHITE (-3160 2860);
WIRE 16 -1 (-3275 3075)(-1725 3075);
FORCEPROP 2 LAST SIG_NAME FM_PVCCIN_CPU1_R_EN
J 0
(-3160 3085);
DISPLAY 0.851064 (-3160 3085);
PAINT WHITE (-3160 3085);
WIRE 16 -1 (-1525 -600)(275 -600);
FORCEPROP 2 LAST SIG_NAME FM_CPU1_SKTOCC_LVT3_PLD_N
J 0
(-935 -590);
DISPLAY 0.851064 (-935 -590);
PAINT WHITE (-935 -590);
WIRE 16 -1 (-1525 -375)(275 -375);
FORCEPROP 2 LAST SIG_NAME FM_CPU0_SKTOCC_LVT3_PLD_N
J 0
(-935 -365);
DISPLAY 0.851064 (-935 -365);
PAINT WHITE (-935 -365);
WIRE 16 -1 (-3275 1500)(-1725 1500);
FORCEPROP 2 LAST SIG_NAME PWRGD_PCH_PWROK_R
J 0
(-3160 1510);
DISPLAY 0.851064 (-3160 1510);
PAINT WHITE (-3160 1510);
WIRE 16 -1 (-1525 1025)(275 1025);
FORCEPROP 2 LAST SIG_NAME PWRGD_P1V8_PCH_AUX_PLD
J 0
(-935 1035);
DISPLAY 0.851064 (-935 1035);
PAINT WHITE (-935 1035);
WIRE 16 -1 (-3275 1725)(-1725 1725);
FORCEPROP 2 LAST SIG_NAME PWRGD_SYS_PWROK_R
J 0
(-3160 1735);
DISPLAY 0.851064 (-3160 1735);
PAINT WHITE (-3160 1735);
WIRE 16 -1 (-3275 1250)(-1725 1250);
FORCEPROP 2 LAST SIG_NAME PWRGD_CPUPWRGD_LVC1
J 0
(-3160 1260);
DISPLAY 0.851064 (-3160 1260);
PAINT WHITE (-3160 1260);
WIRE 16 -1 (-1525 1500)(275 1500);
FORCEPROP 2 LAST SIG_NAME PWRGD_PCH_PWROK
J 0
(-935 1510);
DISPLAY 0.851064 (-935 1510);
PAINT WHITE (-935 1510);
WIRE 16 -1 (1650 -600)(2900 -600);
FORCEPROP 2 LAST SIG_NAME RST_PFR_OVR_SRTC_R
J 0
(1765 -590);
DISPLAY 0.851064 (1765 -590);
PAINT WHITE (1765 -590);
WIRE 16 -1 (3100 -600)(4425 -600);
FORCEPROP 2 LAST SIG_NAME RST_PFR_OVR_SRTC
J 0
(3515 -590);
DISPLAY 0.851064 (3515 -590);
PAINT WHITE (3515 -590);
WIRE 16 -1 (1650 -375)(2900 -375);
FORCEPROP 2 LAST SIG_NAME RST_PFR_OVR_RTC_R
J 0
(1765 -365);
DISPLAY 0.851064 (1765 -365);
PAINT WHITE (1765 -365);
WIRE 16 -1 (3100 -375)(4425 -375);
FORCEPROP 2 LAST SIG_NAME RST_PFR_OVR_RTC
J 0
(3515 -365);
DISPLAY 0.851064 (3515 -365);
PAINT WHITE (3515 -365);
WIRE 16 -1 (1675 4200)(2900 4200);
FORCEPROP 2 LAST SIG_NAME SGPIO_DO_0
J 0
(1790 4210);
DISPLAY 0.851064 (1790 4210);
PAINT WHITE (1790 4210);
WIRE 16 -1 (-3275 1025)(-1725 1025);
FORCEPROP 2 LAST SIG_NAME PWRGD_P1V8_PCH_AUX
J 0
(-3160 1035);
DISPLAY 0.851064 (-3160 1035);
PAINT WHITE (-3160 1035);
WIRE 16 -1 (-1525 2375)(275 2375);
FORCEPROP 2 LAST SIG_NAME FM_PVCCFA_EHV_FIVRA_CPU1_EN
J 0
(-935 2385);
DISPLAY 0.851064 (-935 2385);
PAINT WHITE (-935 2385);
WIRE 16 -1 (-1525 3075)(275 3075);
FORCEPROP 2 LAST SIG_NAME FM_PVCCIN_CPU1_EN
J 0
(-935 3085);
DISPLAY 0.851064 (-935 3085);
PAINT WHITE (-935 3085);
WIRE 16 -1 (-3275 3500)(-1725 3500);
FORCEPROP 2 LAST SIG_NAME FM_PVCCFA_EHV_FIVRA_CPU0_R_EN
J 0
(-3160 3510);
DISPLAY 0.851064 (-3160 3510);
PAINT WHITE (-3160 3510);
WIRE 16 -1 (-1525 3500)(275 3500);
FORCEPROP 2 LAST SIG_NAME FM_PVCCFA_EHV_FIVRA_CPU0_EN
J 0
(-935 3510);
DISPLAY 0.851064 (-935 3510);
PAINT WHITE (-935 3510);
WIRE 16 -1 (-3275 3725)(-1725 3725);
FORCEPROP 2 LAST SIG_NAME FM_PVCCINFAON_CPU0_R_EN
J 0
(-3160 3735);
DISPLAY 0.851064 (-3160 3735);
PAINT WHITE (-3160 3735);
WIRE 16 -1 (-1525 3725)(275 3725);
FORCEPROP 2 LAST SIG_NAME FM_PVCCINFAON_CPU0_EN
J 0
(-935 3735);
DISPLAY 0.851064 (-935 3735);
PAINT WHITE (-935 3735);
WIRE 16 -1 (-3275 3975)(-1725 3975);
FORCEPROP 2 LAST SIG_NAME FM_PVCCFA_EHV_CPU0_R_EN
J 0
(-3160 3985);
DISPLAY 0.851064 (-3160 3985);
PAINT WHITE (-3160 3985);
WIRE 16 -1 (-1525 3975)(275 3975);
FORCEPROP 2 LAST SIG_NAME FM_PVCCFA_EHV_CPU0_EN
J 0
(-935 3985);
DISPLAY 0.851064 (-935 3985);
PAINT WHITE (-935 3985);
WIRE 16 -1 (1675 3500)(2900 3500);
FORCEPROP 2 LAST SIG_NAME SGPIO_LD_0
J 0
(1790 3510);
DISPLAY 0.851064 (1790 3510);
PAINT WHITE (1790 3510);
WIRE 16 -1 (1675 3725)(2900 3725);
FORCEPROP 2 LAST SIG_NAME SGPIO_DI_0
J 0
(1790 3735);
DISPLAY 0.851064 (1790 3735);
PAINT WHITE (1790 3735);
WIRE 16 -1 (1675 3975)(2900 3975);
FORCEPROP 2 LAST SIG_NAME SGPIO_CLK_0
J 0
(1790 3985);
DISPLAY 0.851064 (1790 3985);
PAINT WHITE (1790 3985);
WIRE 16 -1 (-1525 2850)(275 2850);
FORCEPROP 2 LAST SIG_NAME FM_PVCCFA_EHV_CPU1_EN
J 0
(-935 2860);
DISPLAY 0.851064 (-935 2860);
PAINT WHITE (-935 2860);
WIRE 16 -1 (-3275 2600)(-1725 2600);
FORCEPROP 2 LAST SIG_NAME FM_PVCCINFAON_CPU1_R_EN
J 0
(-3160 2610);
DISPLAY 0.851064 (-3160 2610);
PAINT WHITE (-3160 2610);
WIRE 16 -1 (-1525 2600)(275 2600);
FORCEPROP 2 LAST SIG_NAME FM_PVCCINFAON_CPU1_EN
J 0
(-935 2610);
DISPLAY 0.851064 (-935 2610);
PAINT WHITE (-935 2610);
WIRE 16 -1 (-3275 4200)(-1725 4200);
FORCEPROP 2 LAST SIG_NAME FM_PVCCIN_CPU0_R_EN
J 0
(-3160 4210);
DISPLAY 0.851064 (-3160 4210);
PAINT WHITE (-3160 4210);
WIRE 16 -1 (-1525 4200)(275 4200);
FORCEPROP 2 LAST SIG_NAME FM_PVCCIN_CPU0_EN
J 0
(-935 4210);
DISPLAY 0.851064 (-935 4210);
PAINT WHITE (-935 4210);
DOT 1 (-2450 350);
FORCENOTE
20211201 ADD RES TO PDB
(-1575 0) 0;
DISPLAY LEFT (-1575 0);
DISPLAY 1.063830 (-1575 0);
PAINT WHITE (-1575 0);
FORCENOTE
RTC & SRTC
(1450 -125) 0;
DISPLAY LEFT (1450 -125);
DISPLAY 2.000000 (1450 -125);
PAINT YELLOW (1450 -125);
FORCENOTE
SKTOCC
(-3150 -150) 0;
DISPLAY LEFT (-3150 -150);
DISPLAY 2.000000 (-3150 -150);
PAINT YELLOW (-3150 -150);
FORCENOTE
20210902 MODIFY FOR GT
(-3800 4650) 0;
DISPLAY LEFT (-3800 4650);
DISPLAY 2.510638 (-3800 4650);
PAINT PINK (-3800 4650);
FORCENOTE
SGPIO#0
(1800 4425) 0;
DISPLAY LEFT (1800 4425);
DISPLAY 2.000000 (1800 4425);
PAINT YELLOW (1800 4425);
FORCENOTE
PWRGD
(-3150 1925) 0;
DISPLAY LEFT (-3150 1925);
DISPLAY 2.000000 (-3150 1925);
PAINT YELLOW (-3150 1925);
FORCENOTE
SGPIO#1
(1800 3300) 0;
DISPLAY LEFT (1800 3300);
DISPLAY 2.000000 (1800 3300);
PAINT YELLOW (1800 3300);
QUIT
